(kicad_sch (version 20211123) (generator eeschema)

  (paper "A3")

  (title_block
    (title "SA800U (Snapdragon 845) Baseboard")
    (date "2023-10-19")
    (rev "1.0.3")
    (company "Antmicro Ltd.")
    (comment 1 "www.antmicro.com")
  )

  (junction (at 96.901 248.666) (diameter 0) (color 0 0 0 0)
  )
  (junction (at 134.366 248.666) (diameter 0) (color 0 0 0 0)
  )
  (junction (at 290.83 194.31) (diameter 0) (color 0 0 0 0)
  )
  (junction (at 290.83 191.77) (diameter 0) (color 0 0 0 0)
  )
  (junction (at 122.936 258.826) (diameter 0) (color 0 0 0 0)
  )
  (junction (at 316.611 96.647) (diameter 0) (color 0 0 0 0)
  )
  (junction (at 102.616 248.666) (diameter 0) (color 0 0 0 0)
  )
  (junction (at 381.127 60.833) (diameter 0) (color 0 0 0 0)
  )
  (junction (at 145.796 248.666) (diameter 0) (color 0 0 0 0)
  )
  (junction (at 145.796 258.826) (diameter 0) (color 0 0 0 0)
  )
  (junction (at 185.547 161.925) (diameter 0) (color 0 0 0 0)
  )
  (junction (at 122.936 248.666) (diameter 0) (color 0 0 0 0)
  )
  (junction (at 395.097 148.463) (diameter 0) (color 0 0 0 0)
  )
  (junction (at 393.827 63.373) (diameter 0) (color 0 0 0 0)
  )
  (junction (at 381.127 90.043) (diameter 0) (color 0 0 0 0)
  )
  (junction (at 51.181 187.96) (diameter 0) (color 0 0 0 0)
  )
  (junction (at 199.39 184.15) (diameter 0) (color 0 0 0 0)
  )
  (junction (at 381.127 117.983) (diameter 0) (color 0 0 0 0)
  )
  (junction (at 368.427 117.983) (diameter 0) (color 0 0 0 0)
  )
  (junction (at 112.776 258.826) (diameter 0) (color 0 0 0 0)
  )
  (junction (at 393.827 120.523) (diameter 0) (color 0 0 0 0)
  )
  (junction (at 393.827 92.583) (diameter 0) (color 0 0 0 0)
  )
  (junction (at 382.397 145.923) (diameter 0) (color 0 0 0 0)
  )
  (junction (at 368.427 60.833) (diameter 0) (color 0 0 0 0)
  )
  (junction (at 199.39 181.61) (diameter 0) (color 0 0 0 0)
  )
  (junction (at 198.755 194.31) (diameter 0) (color 0 0 0 0)
  )
  (junction (at 134.366 258.826) (diameter 0) (color 0 0 0 0)
  )
  (junction (at 116.84 167.64) (diameter 0) (color 0 0 0 0)
  )
  (junction (at 99.314 248.666) (diameter 0) (color 0 0 0 0)
  )
  (junction (at 368.427 90.043) (diameter 0) (color 0 0 0 0)
  )
  (junction (at 112.776 248.666) (diameter 0) (color 0 0 0 0)
  )
  (junction (at 369.697 145.923) (diameter 0) (color 0 0 0 0)
  )
  (junction (at 116.84 165.1) (diameter 0) (color 0 0 0 0)
  )

  (no_connect (at 207.645 110.49))
  (no_connect (at 273.05 87.63))
  (no_connect (at 38.735 154.94))
  (no_connect (at 257.175 133.35))
  (no_connect (at 194.945 74.93))
  (no_connect (at 120.015 111.76))
  (no_connect (at 121.92 149.86))
  (no_connect (at 57.785 137.16))
  (no_connect (at 107.315 154.94))
  (no_connect (at 120.015 114.3))
  (no_connect (at 120.015 66.04))
  (no_connect (at 57.785 167.64))
  (no_connect (at 57.785 182.88))
  (no_connect (at 273.05 95.25))
  (no_connect (at 274.2692 123.19))
  (no_connect (at 107.315 157.48))
  (no_connect (at 257.175 135.89))
  (no_connect (at 274.2692 125.73))
  (no_connect (at 207.645 171.45))
  (no_connect (at 274.2692 120.65))
  (no_connect (at 120.015 88.9))
  (no_connect (at 257.175 90.17))
  (no_connect (at 207.645 186.69))
  (no_connect (at 38.735 147.32))
  (no_connect (at 41.275 109.22))
  (no_connect (at 120.015 109.22))
  (no_connect (at 107.315 55.88))
  (no_connect (at 257.175 181.61))
  (no_connect (at 273.05 69.85))
  (no_connect (at 45.085 86.36))
  (no_connect (at 207.645 191.77))
  (no_connect (at 193.04 36.83))
  (no_connect (at 120.015 106.68))
  (no_connect (at 45.085 93.98))
  (no_connect (at 207.645 90.17))
  (no_connect (at 207.645 85.09))
  (no_connect (at 273.05 82.55))
  (no_connect (at 207.645 189.23))
  (no_connect (at 207.645 130.81))
  (no_connect (at 207.645 118.11))
  (no_connect (at 57.785 165.1))
  (no_connect (at 120.015 99.06))
  (no_connect (at 194.945 72.39))
  (no_connect (at 107.315 162.56))
  (no_connect (at 121.92 152.4))
  (no_connect (at 38.735 152.4))
  (no_connect (at 257.175 186.69))
  (no_connect (at 207.645 179.07))
  (no_connect (at 45.085 88.9))
  (no_connect (at 207.645 133.35))
  (no_connect (at 57.785 99.06))
  (no_connect (at 121.92 147.32))
  (no_connect (at 41.275 104.14))
  (no_connect (at 41.275 106.68))
  (no_connect (at 207.645 173.99))
  (no_connect (at 45.085 91.44))
  (no_connect (at 257.175 184.15))
  (no_connect (at 45.085 81.28))
  (no_connect (at 57.785 180.34))
  (no_connect (at 274.2692 128.27))
  (no_connect (at 41.275 129.54))
  (no_connect (at 107.315 63.5))
  (no_connect (at 41.275 114.3))
  (no_connect (at 257.175 97.79))
  (no_connect (at 107.315 53.34))
  (no_connect (at 120.015 119.38))
  (no_connect (at 57.785 144.78))
  (no_connect (at 120.015 93.98))
  (no_connect (at 207.645 77.47))
  (no_connect (at 38.735 149.86))
  (no_connect (at 107.315 160.02))
  (no_connect (at 45.085 83.82))
  (no_connect (at 107.315 60.96))
  (no_connect (at 41.275 101.6))
  (no_connect (at 273.05 74.93))
  (no_connect (at 257.175 189.23))
  (no_connect (at 273.05 67.31))
  (no_connect (at 207.645 87.63))
  (no_connect (at 41.275 127))
  (no_connect (at 57.785 162.56))
  (no_connect (at 120.015 86.36))
  (no_connect (at 41.275 124.46))
  (no_connect (at 207.645 125.73))
  (no_connect (at 273.05 100.33))
  (no_connect (at 120.015 101.6))
  (no_connect (at 41.275 111.76))
  (no_connect (at 38.735 157.48))
  (no_connect (at 273.05 72.39))
  (no_connect (at 121.92 144.78))
  (no_connect (at 41.275 119.38))
  (no_connect (at 207.645 115.57))
  (no_connect (at 273.05 77.47))
  (no_connect (at 257.175 115.57))
  (no_connect (at 107.315 58.42))
  (no_connect (at 107.315 116.84))
  (no_connect (at 57.785 121.92))
  (no_connect (at 257.175 92.71))
  (no_connect (at 120.015 104.14))
  (no_connect (at 273.05 85.09))
  (no_connect (at 193.04 39.37))
  (no_connect (at 57.785 185.42))
  (no_connect (at 207.645 128.27))
  (no_connect (at 207.645 176.53))
  (no_connect (at 57.785 96.52))
  (no_connect (at 207.645 120.65))
  (no_connect (at 57.785 132.08))
  (no_connect (at 120.015 91.44))
  (no_connect (at 120.015 96.52))
  (no_connect (at 207.645 82.55))
  (no_connect (at 273.05 80.01))
  (no_connect (at 274.2692 130.81))

  (wire (pts (xy 287.02 270.51) (xy 287.909 270.51))
    (stroke (width 0) (type default) (color 0 0 0 0))
  )
  (polyline (pts (xy 284.988 40.132) (xy 284.988 66.548))
    (stroke (width 0) (type default) (color 0 0 0 0))
  )

  (wire (pts (xy 120.015 111.76) (xy 107.315 111.76))
    (stroke (width 0) (type default) (color 0 0 0 0))
  )
  (wire (pts (xy 316.611 106.807) (xy 316.611 104.267))
    (stroke (width 0) (type default) (color 0 0 0 0))
  )
  (wire (pts (xy 257.175 67.31) (xy 273.05 67.31))
    (stroke (width 0) (type default) (color 0 0 0 0))
  )
  (polyline (pts (xy 275.9964 132.4356) (xy 277.2664 132.4356))
    (stroke (width 0) (type default) (color 0 0 0 0))
  )
  (polyline (pts (xy 289.56 107.315) (xy 288.29 107.315))
    (stroke (width 0) (type default) (color 0 0 0 0))
  )

  (wire (pts (xy 269.875 54.61) (xy 257.175 54.61))
    (stroke (width 0) (type default) (color 0 0 0 0))
  )
  (wire (pts (xy 269.875 44.45) (xy 257.175 44.45))
    (stroke (width 0) (type default) (color 0 0 0 0))
  )
  (wire (pts (xy 194.945 31.75) (xy 207.645 31.75))
    (stroke (width 0) (type default) (color 0 0 0 0))
  )
  (wire (pts (xy 269.875 156.21) (xy 257.175 156.21))
    (stroke (width 0) (type default) (color 0 0 0 0))
  )
  (wire (pts (xy 194.945 46.99) (xy 207.645 46.99))
    (stroke (width 0) (type default) (color 0 0 0 0))
  )
  (wire (pts (xy 368.427 90.043) (xy 381.127 90.043))
    (stroke (width 0) (type default) (color 0 0 0 0))
  )
  (wire (pts (xy 310.515 171.45) (xy 316.23 171.45))
    (stroke (width 0) (type default) (color 0 0 0 0))
  )
  (wire (pts (xy 122.936 256.413) (xy 122.936 258.826))
    (stroke (width 0) (type default) (color 0 0 0 0))
  )
  (wire (pts (xy 269.875 179.07) (xy 257.175 179.07))
    (stroke (width 0) (type default) (color 0 0 0 0))
  )
  (polyline (pts (xy 28.575 173.355) (xy 28.575 169.545))
    (stroke (width 0) (type default) (color 0 0 0 0))
  )

  (wire (pts (xy 120.015 73.66) (xy 107.315 73.66))
    (stroke (width 0) (type default) (color 0 0 0 0))
  )
  (polyline (pts (xy 30.48 160.02) (xy 30.48 145.415))
    (stroke (width 0) (type default) (color 0 0 0 0))
  )

  (wire (pts (xy 392.557 117.983) (xy 393.827 117.983))
    (stroke (width 0) (type default) (color 0 0 0 0))
  )
  (polyline (pts (xy 122.555 94.615) (xy 123.825 94.615))
    (stroke (width 0) (type default) (color 0 0 0 0))
  )

  (wire (pts (xy 102.616 251.206) (xy 102.616 248.666))
    (stroke (width 0) (type default) (color 0 0 0 0))
  )
  (wire (pts (xy 287.02 265.43) (xy 290.83 265.43))
    (stroke (width 0) (type default) (color 0 0 0 0))
  )
  (wire (pts (xy 107.315 149.86) (xy 121.92 149.86))
    (stroke (width 0) (type default) (color 0 0 0 0))
  )
  (polyline (pts (xy 190.5 76.2) (xy 190.5 72.39))
    (stroke (width 0) (type default) (color 0 0 0 0))
  )
  (polyline (pts (xy 182.245 80.01) (xy 180.975 80.01))
    (stroke (width 0) (type default) (color 0 0 0 0))
  )

  (wire (pts (xy 41.275 114.3) (xy 57.785 114.3))
    (stroke (width 0) (type default) (color 0 0 0 0))
  )
  (wire (pts (xy 96.901 251.206) (xy 96.901 248.666))
    (stroke (width 0) (type default) (color 0 0 0 0))
  )
  (wire (pts (xy 116.84 165.1) (xy 120.015 165.1))
    (stroke (width 0) (type default) (color 0 0 0 0))
  )
  (wire (pts (xy 393.827 90.043) (xy 393.827 92.583))
    (stroke (width 0) (type default) (color 0 0 0 0))
  )
  (wire (pts (xy 193.04 36.83) (xy 207.645 36.83))
    (stroke (width 0) (type default) (color 0 0 0 0))
  )
  (wire (pts (xy 381.127 60.833) (xy 382.397 60.833))
    (stroke (width 0) (type default) (color 0 0 0 0))
  )
  (wire (pts (xy 205.105 166.37) (xy 205.105 167.005))
    (stroke (width 0) (type default) (color 0 0 0 0))
  )
  (polyline (pts (xy 289.56 118.745) (xy 289.56 107.315))
    (stroke (width 0) (type default) (color 0 0 0 0))
  )
  (polyline (pts (xy 284.988 68.072) (xy 283.718 68.072))
    (stroke (width 0) (type default) (color 0 0 0 0))
  )
  (polyline (pts (xy 122.555 109.855) (xy 123.825 109.855))
    (stroke (width 0) (type default) (color 0 0 0 0))
  )

  (wire (pts (xy 134.366 248.666) (xy 145.796 248.666))
    (stroke (width 0) (type default) (color 0 0 0 0))
  )
  (wire (pts (xy 269.875 173.99) (xy 257.175 173.99))
    (stroke (width 0) (type default) (color 0 0 0 0))
  )
  (wire (pts (xy 38.735 149.86) (xy 57.785 149.86))
    (stroke (width 0) (type default) (color 0 0 0 0))
  )
  (polyline (pts (xy 138.43 121.031) (xy 138.43 143.51))
    (stroke (width 0) (type default) (color 0 0 0 0))
  )

  (wire (pts (xy 257.175 72.39) (xy 273.05 72.39))
    (stroke (width 0) (type default) (color 0 0 0 0))
  )
  (polyline (pts (xy 138.303 143.256) (xy 137.033 143.256))
    (stroke (width 0) (type default) (color 0 0 0 0))
  )

  (wire (pts (xy 290.83 264.16) (xy 290.83 265.43))
    (stroke (width 0) (type default) (color 0 0 0 0))
  )
  (wire (pts (xy 112.776 258.826) (xy 102.616 258.826))
    (stroke (width 0) (type default) (color 0 0 0 0))
  )
  (wire (pts (xy 290.83 194.31) (xy 290.83 196.85))
    (stroke (width 0) (type default) (color 0 0 0 0))
  )
  (wire (pts (xy 269.875 31.75) (xy 257.175 31.75))
    (stroke (width 0) (type default) (color 0 0 0 0))
  )
  (wire (pts (xy 45.085 116.84) (xy 57.785 116.84))
    (stroke (width 0) (type default) (color 0 0 0 0))
  )
  (wire (pts (xy 107.315 147.32) (xy 121.92 147.32))
    (stroke (width 0) (type default) (color 0 0 0 0))
  )
  (polyline (pts (xy 288.29 118.745) (xy 289.56 118.745))
    (stroke (width 0) (type default) (color 0 0 0 0))
  )

  (wire (pts (xy 378.46 206.375) (xy 381 206.375))
    (stroke (width 0) (type default) (color 0 0 0 0))
  )
  (wire (pts (xy 207.645 166.37) (xy 205.105 166.37))
    (stroke (width 0) (type default) (color 0 0 0 0))
  )
  (wire (pts (xy 207.645 72.39) (xy 194.945 72.39))
    (stroke (width 0) (type default) (color 0 0 0 0))
  )
  (wire (pts (xy 382.397 63.373) (xy 381.127 63.373))
    (stroke (width 0) (type default) (color 0 0 0 0))
  )
  (polyline (pts (xy 139.065 28.575) (xy 139.065 51.816))
    (stroke (width 0) (type default) (color 0 0 0 0))
  )
  (polyline (pts (xy 175.387 145.034) (xy 176.657 145.034))
    (stroke (width 0) (type default) (color 0 0 0 0))
  )
  (polyline (pts (xy 29.845 174.625) (xy 28.575 174.625))
    (stroke (width 0) (type default) (color 0 0 0 0))
  )

  (wire (pts (xy 257.175 128.27) (xy 274.2692 128.27))
    (stroke (width 0) (type default) (color 0 0 0 0))
  )
  (wire (pts (xy 120.015 114.3) (xy 107.315 114.3))
    (stroke (width 0) (type default) (color 0 0 0 0))
  )
  (polyline (pts (xy 283.718 40.132) (xy 284.988 40.132))
    (stroke (width 0) (type default) (color 0 0 0 0))
  )

  (wire (pts (xy 194.945 146.05) (xy 207.645 146.05))
    (stroke (width 0) (type default) (color 0 0 0 0))
  )
  (wire (pts (xy 393.827 117.983) (xy 393.827 120.523))
    (stroke (width 0) (type default) (color 0 0 0 0))
  )
  (wire (pts (xy 290.83 191.77) (xy 290.83 194.31))
    (stroke (width 0) (type default) (color 0 0 0 0))
  )
  (polyline (pts (xy 288.29 157.353) (xy 288.29 142.367))
    (stroke (width 0) (type default) (color 0 0 0 0))
  )

  (wire (pts (xy 207.645 163.83) (xy 205.105 163.83))
    (stroke (width 0) (type default) (color 0 0 0 0))
  )
  (wire (pts (xy 51.181 187.325) (xy 51.181 187.96))
    (stroke (width 0) (type default) (color 0 0 0 0))
  )
  (polyline (pts (xy 33.02 54.991) (xy 31.75 54.991))
    (stroke (width 0) (type default) (color 0 0 0 0))
  )

  (wire (pts (xy 257.175 87.63) (xy 273.05 87.63))
    (stroke (width 0) (type default) (color 0 0 0 0))
  )
  (wire (pts (xy 205.105 167.005) (xy 193.04 167.005))
    (stroke (width 0) (type default) (color 0 0 0 0))
  )
  (wire (pts (xy 134.366 248.666) (xy 134.366 251.206))
    (stroke (width 0) (type default) (color 0 0 0 0))
  )
  (wire (pts (xy 102.616 258.826) (xy 102.616 256.286))
    (stroke (width 0) (type default) (color 0 0 0 0))
  )
  (wire (pts (xy 194.945 34.29) (xy 207.645 34.29))
    (stroke (width 0) (type default) (color 0 0 0 0))
  )
  (wire (pts (xy 51.181 187.96) (xy 57.785 187.96))
    (stroke (width 0) (type default) (color 0 0 0 0))
  )
  (wire (pts (xy 282.575 191.77) (xy 290.83 191.77))
    (stroke (width 0) (type default) (color 0 0 0 0))
  )
  (wire (pts (xy 368.427 117.983) (xy 381.127 117.983))
    (stroke (width 0) (type default) (color 0 0 0 0))
  )
  (polyline (pts (xy 38.735 106.68) (xy 37.465 106.68))
    (stroke (width 0) (type default) (color 0 0 0 0))
  )

  (wire (pts (xy 45.085 35.56) (xy 57.785 35.56))
    (stroke (width 0) (type default) (color 0 0 0 0))
  )
  (wire (pts (xy 112.776 256.286) (xy 112.776 258.826))
    (stroke (width 0) (type default) (color 0 0 0 0))
  )
  (wire (pts (xy 122.936 258.826) (xy 112.776 258.826))
    (stroke (width 0) (type default) (color 0 0 0 0))
  )
  (wire (pts (xy 107.315 88.9) (xy 120.015 88.9))
    (stroke (width 0) (type default) (color 0 0 0 0))
  )
  (wire (pts (xy 107.315 134.62) (xy 120.015 134.62))
    (stroke (width 0) (type default) (color 0 0 0 0))
  )
  (wire (pts (xy 55.372 190.5) (xy 55.372 192.786))
    (stroke (width 0) (type default) (color 0 0 0 0))
  )
  (polyline (pts (xy 138.43 143.51) (xy 137.16 143.51))
    (stroke (width 0) (type default) (color 0 0 0 0))
  )

  (wire (pts (xy 194.945 95.25) (xy 207.645 95.25))
    (stroke (width 0) (type default) (color 0 0 0 0))
  )
  (wire (pts (xy 120.015 139.7) (xy 107.315 139.7))
    (stroke (width 0) (type default) (color 0 0 0 0))
  )
  (wire (pts (xy 107.315 83.82) (xy 120.015 83.82))
    (stroke (width 0) (type default) (color 0 0 0 0))
  )
  (wire (pts (xy 99.314 248.666) (xy 102.616 248.666))
    (stroke (width 0) (type default) (color 0 0 0 0))
  )
  (wire (pts (xy 112.776 248.666) (xy 112.776 251.206))
    (stroke (width 0) (type default) (color 0 0 0 0))
  )
  (wire (pts (xy 120.015 50.8) (xy 107.315 50.8))
    (stroke (width 0) (type default) (color 0 0 0 0))
  )
  (wire (pts (xy 269.875 151.13) (xy 257.175 151.13))
    (stroke (width 0) (type default) (color 0 0 0 0))
  )
  (wire (pts (xy 155.956 258.826) (xy 155.956 256.286))
    (stroke (width 0) (type default) (color 0 0 0 0))
  )
  (wire (pts (xy 381.127 120.523) (xy 381.127 117.983))
    (stroke (width 0) (type default) (color 0 0 0 0))
  )
  (wire (pts (xy 120.015 35.56) (xy 107.315 35.56))
    (stroke (width 0) (type default) (color 0 0 0 0))
  )
  (wire (pts (xy 269.875 59.69) (xy 257.175 59.69))
    (stroke (width 0) (type default) (color 0 0 0 0))
  )
  (wire (pts (xy 45.085 88.9) (xy 57.785 88.9))
    (stroke (width 0) (type default) (color 0 0 0 0))
  )
  (wire (pts (xy 120.015 104.14) (xy 107.315 104.14))
    (stroke (width 0) (type default) (color 0 0 0 0))
  )
  (wire (pts (xy 274.32 265.43) (xy 262.255 265.43))
    (stroke (width 0) (type default) (color 0 0 0 0))
  )
  (polyline (pts (xy 31.75 79.502) (xy 33.02 79.502))
    (stroke (width 0) (type default) (color 0 0 0 0))
  )

  (wire (pts (xy 122.936 248.666) (xy 122.936 251.333))
    (stroke (width 0) (type default) (color 0 0 0 0))
  )
  (wire (pts (xy 379.095 232.41) (xy 381.635 232.41))
    (stroke (width 0) (type default) (color 0 0 0 0))
  )
  (wire (pts (xy 206.502 201.93) (xy 207.645 201.93))
    (stroke (width 0) (type default) (color 0 0 0 0))
  )
  (wire (pts (xy 393.827 120.523) (xy 393.827 121.793))
    (stroke (width 0) (type default) (color 0 0 0 0))
  )
  (wire (pts (xy 316.611 96.647) (xy 324.739 96.647))
    (stroke (width 0) (type default) (color 0 0 0 0))
  )
  (polyline (pts (xy 180.975 70.993) (xy 181.102 40.894))
    (stroke (width 0) (type default) (color 0 0 0 0))
  )

  (wire (pts (xy 368.427 130.683) (xy 368.427 131.318))
    (stroke (width 0) (type default) (color 0 0 0 0))
  )
  (wire (pts (xy 194.945 74.93) (xy 207.645 74.93))
    (stroke (width 0) (type default) (color 0 0 0 0))
  )
  (wire (pts (xy 120.015 30.48) (xy 107.315 30.48))
    (stroke (width 0) (type default) (color 0 0 0 0))
  )
  (wire (pts (xy 45.085 63.5) (xy 57.785 63.5))
    (stroke (width 0) (type default) (color 0 0 0 0))
  )
  (wire (pts (xy 269.875 158.75) (xy 257.175 158.75))
    (stroke (width 0) (type default) (color 0 0 0 0))
  )
  (wire (pts (xy 257.175 191.77) (xy 277.495 191.77))
    (stroke (width 0) (type default) (color 0 0 0 0))
  )
  (wire (pts (xy 145.796 256.286) (xy 145.796 258.826))
    (stroke (width 0) (type default) (color 0 0 0 0))
  )
  (polyline (pts (xy 30.48 145.415) (xy 32.385 145.415))
    (stroke (width 0) (type default) (color 0 0 0 0))
  )
  (polyline (pts (xy 134.747 67.437) (xy 133.477 67.437))
    (stroke (width 0) (type default) (color 0 0 0 0))
  )
  (polyline (pts (xy 288.29 163.195) (xy 287.02 163.195))
    (stroke (width 0) (type default) (color 0 0 0 0))
  )

  (wire (pts (xy 207.645 57.15) (xy 194.945 57.15))
    (stroke (width 0) (type default) (color 0 0 0 0))
  )
  (polyline (pts (xy 38.735 122.555) (xy 37.465 122.555))
    (stroke (width 0) (type default) (color 0 0 0 0))
  )
  (polyline (pts (xy 28.575 134.62) (xy 27.305 134.62))
    (stroke (width 0) (type default) (color 0 0 0 0))
  )

  (wire (pts (xy 369.697 158.623) (xy 369.697 159.258))
    (stroke (width 0) (type default) (color 0 0 0 0))
  )
  (wire (pts (xy 45.085 38.1) (xy 57.785 38.1))
    (stroke (width 0) (type default) (color 0 0 0 0))
  )
  (wire (pts (xy 120.015 129.54) (xy 107.315 129.54))
    (stroke (width 0) (type default) (color 0 0 0 0))
  )
  (polyline (pts (xy 33.02 29.591) (xy 31.75 29.591))
    (stroke (width 0) (type default) (color 0 0 0 0))
  )

  (wire (pts (xy 122.936 248.666) (xy 134.366 248.666))
    (stroke (width 0) (type default) (color 0 0 0 0))
  )
  (wire (pts (xy 393.827 60.833) (xy 393.827 63.373))
    (stroke (width 0) (type default) (color 0 0 0 0))
  )
  (polyline (pts (xy 277.2664 132.4356) (xy 277.2664 119.7356))
    (stroke (width 0) (type default) (color 0 0 0 0))
  )
  (polyline (pts (xy 41.91 80.645) (xy 43.18 80.645))
    (stroke (width 0) (type default) (color 0 0 0 0))
  )
  (polyline (pts (xy 179.07 113.03) (xy 177.8 113.03))
    (stroke (width 0) (type default) (color 0 0 0 0))
  )

  (wire (pts (xy 45.085 45.72) (xy 57.785 45.72))
    (stroke (width 0) (type default) (color 0 0 0 0))
  )
  (polyline (pts (xy 122.428 115.443) (xy 125.095 115.443))
    (stroke (width 0) (type default) (color 0 0 0 0))
  )

  (wire (pts (xy 107.315 33.02) (xy 120.015 33.02))
    (stroke (width 0) (type default) (color 0 0 0 0))
  )
  (wire (pts (xy 324.739 109.347) (xy 324.739 104.267))
    (stroke (width 0) (type default) (color 0 0 0 0))
  )
  (wire (pts (xy 145.796 248.666) (xy 145.796 251.206))
    (stroke (width 0) (type default) (color 0 0 0 0))
  )
  (wire (pts (xy 368.427 117.983) (xy 358.267 117.983))
    (stroke (width 0) (type default) (color 0 0 0 0))
  )
  (wire (pts (xy 282.575 194.31) (xy 290.83 194.31))
    (stroke (width 0) (type default) (color 0 0 0 0))
  )
  (polyline (pts (xy 277.2664 119.7356) (xy 275.9964 119.7356))
    (stroke (width 0) (type default) (color 0 0 0 0))
  )

  (wire (pts (xy 107.315 40.64) (xy 120.015 40.64))
    (stroke (width 0) (type default) (color 0 0 0 0))
  )
  (wire (pts (xy 45.085 91.44) (xy 57.785 91.44))
    (stroke (width 0) (type default) (color 0 0 0 0))
  )
  (wire (pts (xy 45.085 93.98) (xy 57.785 93.98))
    (stroke (width 0) (type default) (color 0 0 0 0))
  )
  (wire (pts (xy 269.875 62.23) (xy 257.175 62.23))
    (stroke (width 0) (type default) (color 0 0 0 0))
  )
  (wire (pts (xy 285.75 176.53) (xy 285.75 180.34))
    (stroke (width 0) (type default) (color 0 0 0 0))
  )
  (wire (pts (xy 207.645 105.41) (xy 194.945 105.41))
    (stroke (width 0) (type default) (color 0 0 0 0))
  )
  (wire (pts (xy 315.341 106.807) (xy 316.611 106.807))
    (stroke (width 0) (type default) (color 0 0 0 0))
  )
  (wire (pts (xy 383.667 148.463) (xy 382.397 148.463))
    (stroke (width 0) (type default) (color 0 0 0 0))
  )
  (wire (pts (xy 290.83 255.27) (xy 290.83 259.08))
    (stroke (width 0) (type default) (color 0 0 0 0))
  )
  (polyline (pts (xy 179.07 100.965) (xy 177.8 100.965))
    (stroke (width 0) (type default) (color 0 0 0 0))
  )

  (wire (pts (xy 207.645 80.01) (xy 194.945 80.01))
    (stroke (width 0) (type default) (color 0 0 0 0))
  )
  (wire (pts (xy 257.175 69.85) (xy 273.05 69.85))
    (stroke (width 0) (type default) (color 0 0 0 0))
  )
  (wire (pts (xy 41.275 127) (xy 57.785 127))
    (stroke (width 0) (type default) (color 0 0 0 0))
  )
  (polyline (pts (xy 288.29 157.734) (xy 287.02 157.734))
    (stroke (width 0) (type default) (color 0 0 0 0))
  )

  (wire (pts (xy 192.786 158.75) (xy 207.645 158.75))
    (stroke (width 0) (type default) (color 0 0 0 0))
  )
  (wire (pts (xy 107.315 124.46) (xy 120.015 124.46))
    (stroke (width 0) (type default) (color 0 0 0 0))
  )
  (wire (pts (xy 269.875 46.99) (xy 257.175 46.99))
    (stroke (width 0) (type default) (color 0 0 0 0))
  )
  (wire (pts (xy 393.827 92.583) (xy 393.827 93.853))
    (stroke (width 0) (type default) (color 0 0 0 0))
  )
  (wire (pts (xy 282.575 196.85) (xy 290.83 196.85))
    (stroke (width 0) (type default) (color 0 0 0 0))
  )
  (wire (pts (xy 41.275 111.76) (xy 57.785 111.76))
    (stroke (width 0) (type default) (color 0 0 0 0))
  )
  (polyline (pts (xy 31.75 29.591) (xy 31.75 54.229))
    (stroke (width 0) (type default) (color 0 0 0 0))
  )
  (polyline (pts (xy 31.75 54.991) (xy 31.75 79.502))
    (stroke (width 0) (type default) (color 0 0 0 0))
  )
  (polyline (pts (xy 175.387 154.686) (xy 175.387 145.034))
    (stroke (width 0) (type default) (color 0 0 0 0))
  )

  (wire (pts (xy 381.127 90.043) (xy 382.397 90.043))
    (stroke (width 0) (type default) (color 0 0 0 0))
  )
  (polyline (pts (xy 288.29 176.53) (xy 287.02 176.53))
    (stroke (width 0) (type default) (color 0 0 0 0))
  )

  (wire (pts (xy 207.645 143.51) (xy 194.945 143.51))
    (stroke (width 0) (type default) (color 0 0 0 0))
  )
  (wire (pts (xy 392.557 60.833) (xy 393.827 60.833))
    (stroke (width 0) (type default) (color 0 0 0 0))
  )
  (wire (pts (xy 269.875 64.77) (xy 257.175 64.77))
    (stroke (width 0) (type default) (color 0 0 0 0))
  )
  (wire (pts (xy 194.945 69.85) (xy 207.645 69.85))
    (stroke (width 0) (type default) (color 0 0 0 0))
  )
  (wire (pts (xy 120.015 121.92) (xy 107.315 121.92))
    (stroke (width 0) (type default) (color 0 0 0 0))
  )
  (wire (pts (xy 257.175 123.19) (xy 274.2692 123.19))
    (stroke (width 0) (type default) (color 0 0 0 0))
  )
  (polyline (pts (xy 28.575 139.7) (xy 27.305 139.7))
    (stroke (width 0) (type default) (color 0 0 0 0))
  )
  (polyline (pts (xy 175.26 144.653) (xy 175.26 134.874))
    (stroke (width 0) (type default) (color 0 0 0 0))
  )
  (polyline (pts (xy 285.115 76.2) (xy 284.988 68.072))
    (stroke (width 0) (type default) (color 0 0 0 0))
  )
  (polyline (pts (xy 177.8 34.925) (xy 177.8 31.115))
    (stroke (width 0) (type default) (color 0 0 0 0))
  )

  (wire (pts (xy 257.175 105.41) (xy 269.875 105.41))
    (stroke (width 0) (type default) (color 0 0 0 0))
  )
  (wire (pts (xy 257.175 199.39) (xy 277.495 199.39))
    (stroke (width 0) (type default) (color 0 0 0 0))
  )
  (wire (pts (xy 193.04 39.37) (xy 207.645 39.37))
    (stroke (width 0) (type default) (color 0 0 0 0))
  )
  (polyline (pts (xy 123.19 66.04) (xy 121.92 66.04))
    (stroke (width 0) (type default) (color 0 0 0 0))
  )

  (wire (pts (xy 381.127 60.833) (xy 368.427 60.833))
    (stroke (width 0) (type default) (color 0 0 0 0))
  )
  (wire (pts (xy 194.945 64.77) (xy 207.645 64.77))
    (stroke (width 0) (type default) (color 0 0 0 0))
  )
  (wire (pts (xy 41.275 106.68) (xy 57.785 106.68))
    (stroke (width 0) (type default) (color 0 0 0 0))
  )
  (polyline (pts (xy 38.735 111.76) (xy 37.465 111.76))
    (stroke (width 0) (type default) (color 0 0 0 0))
  )
  (polyline (pts (xy 179.07 34.925) (xy 177.8 34.925))
    (stroke (width 0) (type default) (color 0 0 0 0))
  )

  (wire (pts (xy 145.796 248.666) (xy 155.956 248.666))
    (stroke (width 0) (type default) (color 0 0 0 0))
  )
  (wire (pts (xy 83.566 248.666) (xy 96.901 248.666))
    (stroke (width 0) (type default) (color 0 0 0 0))
  )
  (wire (pts (xy 107.315 142.24) (xy 120.015 142.24))
    (stroke (width 0) (type default) (color 0 0 0 0))
  )
  (wire (pts (xy 257.175 80.01) (xy 273.05 80.01))
    (stroke (width 0) (type default) (color 0 0 0 0))
  )
  (polyline (pts (xy 287.02 169.545) (xy 288.29 169.545))
    (stroke (width 0) (type default) (color 0 0 0 0))
  )

  (wire (pts (xy 380.365 242.57) (xy 368.3 242.57))
    (stroke (width 0) (type default) (color 0 0 0 0))
  )
  (wire (pts (xy 107.315 38.1) (xy 120.015 38.1))
    (stroke (width 0) (type default) (color 0 0 0 0))
  )
  (wire (pts (xy 269.875 153.67) (xy 257.175 153.67))
    (stroke (width 0) (type default) (color 0 0 0 0))
  )
  (wire (pts (xy 120.015 127) (xy 107.315 127))
    (stroke (width 0) (type default) (color 0 0 0 0))
  )
  (wire (pts (xy 194.945 54.61) (xy 207.645 54.61))
    (stroke (width 0) (type default) (color 0 0 0 0))
  )
  (polyline (pts (xy 38.1 119.38) (xy 36.83 119.38))
    (stroke (width 0) (type default) (color 0 0 0 0))
  )

  (wire (pts (xy 286.385 199.39) (xy 286.385 200.66))
    (stroke (width 0) (type default) (color 0 0 0 0))
  )
  (wire (pts (xy 120.015 106.68) (xy 107.315 106.68))
    (stroke (width 0) (type default) (color 0 0 0 0))
  )
  (polyline (pts (xy 38.735 109.855) (xy 37.465 109.855))
    (stroke (width 0) (type default) (color 0 0 0 0))
  )
  (polyline (pts (xy 288.29 170.18) (xy 287.02 170.18))
    (stroke (width 0) (type default) (color 0 0 0 0))
  )
  (polyline (pts (xy 28.575 178.435) (xy 29.845 178.435))
    (stroke (width 0) (type default) (color 0 0 0 0))
  )

  (wire (pts (xy 269.875 34.29) (xy 257.175 34.29))
    (stroke (width 0) (type default) (color 0 0 0 0))
  )
  (wire (pts (xy 257.175 74.93) (xy 273.05 74.93))
    (stroke (width 0) (type default) (color 0 0 0 0))
  )
  (polyline (pts (xy 288.29 142.367) (xy 287.02 142.367))
    (stroke (width 0) (type default) (color 0 0 0 0))
  )

  (wire (pts (xy 38.735 147.32) (xy 57.785 147.32))
    (stroke (width 0) (type default) (color 0 0 0 0))
  )
  (polyline (pts (xy 288.29 169.545) (xy 288.29 165.1))
    (stroke (width 0) (type default) (color 0 0 0 0))
  )

  (wire (pts (xy 387.985 232.41) (xy 387.985 233.68))
    (stroke (width 0) (type default) (color 0 0 0 0))
  )
  (wire (pts (xy 392.557 90.043) (xy 393.827 90.043))
    (stroke (width 0) (type default) (color 0 0 0 0))
  )
  (polyline (pts (xy 125.095 115.443) (xy 125.095 111.125))
    (stroke (width 0) (type default) (color 0 0 0 0))
  )

  (wire (pts (xy 207.645 29.21) (xy 185.42 29.21))
    (stroke (width 0) (type default) (color 0 0 0 0))
  )
  (wire (pts (xy 45.085 172.72) (xy 57.785 172.72))
    (stroke (width 0) (type default) (color 0 0 0 0))
  )
  (wire (pts (xy 45.085 139.7) (xy 57.785 139.7))
    (stroke (width 0) (type default) (color 0 0 0 0))
  )
  (wire (pts (xy 269.875 138.43) (xy 257.175 138.43))
    (stroke (width 0) (type default) (color 0 0 0 0))
  )
  (wire (pts (xy 45.085 53.34) (xy 57.785 53.34))
    (stroke (width 0) (type default) (color 0 0 0 0))
  )
  (wire (pts (xy 45.085 60.96) (xy 57.785 60.96))
    (stroke (width 0) (type default) (color 0 0 0 0))
  )
  (wire (pts (xy 207.645 151.13) (xy 194.945 151.13))
    (stroke (width 0) (type default) (color 0 0 0 0))
  )
  (wire (pts (xy 369.57 232.41) (xy 371.475 232.41))
    (stroke (width 0) (type default) (color 0 0 0 0))
  )
  (wire (pts (xy 55.372 190.5) (xy 57.785 190.5))
    (stroke (width 0) (type default) (color 0 0 0 0))
  )
  (wire (pts (xy 120.015 119.38) (xy 107.315 119.38))
    (stroke (width 0) (type default) (color 0 0 0 0))
  )
  (polyline (pts (xy 285.115 28.575) (xy 283.845 28.575))
    (stroke (width 0) (type default) (color 0 0 0 0))
  )
  (polyline (pts (xy 191.77 76.2) (xy 190.5 76.2))
    (stroke (width 0) (type default) (color 0 0 0 0))
  )
  (polyline (pts (xy 300.355 247.65) (xy 300.355 251.46))
    (stroke (width 0) (type default) (color 0 0 0 0))
  )

  (wire (pts (xy 122.936 258.826) (xy 134.366 258.826))
    (stroke (width 0) (type default) (color 0 0 0 0))
  )
  (wire (pts (xy 194.945 49.53) (xy 207.645 49.53))
    (stroke (width 0) (type default) (color 0 0 0 0))
  )
  (wire (pts (xy 33.909 187.96) (xy 51.181 187.96))
    (stroke (width 0) (type default) (color 0 0 0 0))
  )
  (wire (pts (xy 207.645 148.59) (xy 194.945 148.59))
    (stroke (width 0) (type default) (color 0 0 0 0))
  )
  (wire (pts (xy 207.645 67.31) (xy 194.945 67.31))
    (stroke (width 0) (type default) (color 0 0 0 0))
  )
  (wire (pts (xy 269.875 148.59) (xy 257.175 148.59))
    (stroke (width 0) (type default) (color 0 0 0 0))
  )
  (wire (pts (xy 194.945 153.67) (xy 207.645 153.67))
    (stroke (width 0) (type default) (color 0 0 0 0))
  )
  (polyline (pts (xy 134.747 84.836) (xy 134.747 67.437))
    (stroke (width 0) (type default) (color 0 0 0 0))
  )
  (polyline (pts (xy 283.718 97.282) (xy 285.115 97.282))
    (stroke (width 0) (type default) (color 0 0 0 0))
  )

  (wire (pts (xy 381 181.61) (xy 379.095 181.61))
    (stroke (width 0) (type default) (color 0 0 0 0))
  )
  (wire (pts (xy 369.697 145.923) (xy 369.697 147.193))
    (stroke (width 0) (type default) (color 0 0 0 0))
  )
  (wire (pts (xy 380.365 191.77) (xy 368.3 191.77))
    (stroke (width 0) (type default) (color 0 0 0 0))
  )
  (wire (pts (xy 395.097 148.463) (xy 395.097 149.733))
    (stroke (width 0) (type default) (color 0 0 0 0))
  )
  (wire (pts (xy 207.645 52.07) (xy 194.945 52.07))
    (stroke (width 0) (type default) (color 0 0 0 0))
  )
  (wire (pts (xy 107.315 165.1) (xy 116.84 165.1))
    (stroke (width 0) (type default) (color 0 0 0 0))
  )
  (wire (pts (xy 194.945 44.45) (xy 207.645 44.45))
    (stroke (width 0) (type default) (color 0 0 0 0))
  )
  (wire (pts (xy 381.127 92.583) (xy 381.127 90.043))
    (stroke (width 0) (type default) (color 0 0 0 0))
  )
  (polyline (pts (xy 41.91 94.742) (xy 41.91 80.645))
    (stroke (width 0) (type default) (color 0 0 0 0))
  )
  (polyline (pts (xy 288.29 165.1) (xy 287.02 165.1))
    (stroke (width 0) (type default) (color 0 0 0 0))
  )

  (wire (pts (xy 45.085 43.18) (xy 57.785 43.18))
    (stroke (width 0) (type default) (color 0 0 0 0))
  )
  (wire (pts (xy 45.085 86.36) (xy 57.785 86.36))
    (stroke (width 0) (type default) (color 0 0 0 0))
  )
  (wire (pts (xy 282.575 199.39) (xy 286.385 199.39))
    (stroke (width 0) (type default) (color 0 0 0 0))
  )
  (wire (pts (xy 45.085 30.48) (xy 57.785 30.48))
    (stroke (width 0) (type default) (color 0 0 0 0))
  )
  (wire (pts (xy 269.875 161.29) (xy 257.175 161.29))
    (stroke (width 0) (type default) (color 0 0 0 0))
  )
  (wire (pts (xy 269.875 143.51) (xy 257.175 143.51))
    (stroke (width 0) (type default) (color 0 0 0 0))
  )
  (wire (pts (xy 287.909 276.86) (xy 287.909 270.51))
    (stroke (width 0) (type default) (color 0 0 0 0))
  )
  (wire (pts (xy 41.275 101.6) (xy 57.785 101.6))
    (stroke (width 0) (type default) (color 0 0 0 0))
  )
  (wire (pts (xy 257.175 85.09) (xy 273.05 85.09))
    (stroke (width 0) (type default) (color 0 0 0 0))
  )
  (wire (pts (xy 45.085 73.66) (xy 57.785 73.66))
    (stroke (width 0) (type default) (color 0 0 0 0))
  )
  (wire (pts (xy 41.275 124.46) (xy 57.785 124.46))
    (stroke (width 0) (type default) (color 0 0 0 0))
  )
  (wire (pts (xy 393.827 63.373) (xy 393.827 64.643))
    (stroke (width 0) (type default) (color 0 0 0 0))
  )
  (polyline (pts (xy 137.16 121.031) (xy 138.43 121.031))
    (stroke (width 0) (type default) (color 0 0 0 0))
  )

  (wire (pts (xy 269.875 118.11) (xy 257.175 118.11))
    (stroke (width 0) (type default) (color 0 0 0 0))
  )
  (wire (pts (xy 290.83 267.97) (xy 290.83 271.78))
    (stroke (width 0) (type default) (color 0 0 0 0))
  )
  (wire (pts (xy 257.175 77.47) (xy 273.05 77.47))
    (stroke (width 0) (type default) (color 0 0 0 0))
  )
  (wire (pts (xy 355.727 145.923) (xy 349.377 145.923))
    (stroke (width 0) (type default) (color 0 0 0 0))
  )
  (polyline (pts (xy 288.29 106.045) (xy 289.56 106.045))
    (stroke (width 0) (type default) (color 0 0 0 0))
  )

  (wire (pts (xy 368.427 90.043) (xy 368.427 91.313))
    (stroke (width 0) (type default) (color 0 0 0 0))
  )
  (wire (pts (xy 368.427 60.833) (xy 368.427 62.103))
    (stroke (width 0) (type default) (color 0 0 0 0))
  )
  (polyline (pts (xy 182.245 70.993) (xy 180.975 70.993))
    (stroke (width 0) (type default) (color 0 0 0 0))
  )

  (wire (pts (xy 41.275 119.38) (xy 57.785 119.38))
    (stroke (width 0) (type default) (color 0 0 0 0))
  )
  (polyline (pts (xy 289.56 106.045) (xy 289.56 102.235))
    (stroke (width 0) (type default) (color 0 0 0 0))
  )

  (wire (pts (xy 393.827 145.923) (xy 395.097 145.923))
    (stroke (width 0) (type default) (color 0 0 0 0))
  )
  (polyline (pts (xy 176.657 154.686) (xy 175.387 154.686))
    (stroke (width 0) (type default) (color 0 0 0 0))
  )

  (wire (pts (xy 387.35 206.375) (xy 387.35 207.645))
    (stroke (width 0) (type default) (color 0 0 0 0))
  )
  (wire (pts (xy 269.875 146.05) (xy 257.175 146.05))
    (stroke (width 0) (type default) (color 0 0 0 0))
  )
  (wire (pts (xy 134.366 258.826) (xy 145.796 258.826))
    (stroke (width 0) (type default) (color 0 0 0 0))
  )
  (wire (pts (xy 324.739 96.647) (xy 324.739 99.187))
    (stroke (width 0) (type default) (color 0 0 0 0))
  )
  (wire (pts (xy 45.085 175.26) (xy 57.785 175.26))
    (stroke (width 0) (type default) (color 0 0 0 0))
  )
  (wire (pts (xy 145.796 258.826) (xy 155.956 258.826))
    (stroke (width 0) (type default) (color 0 0 0 0))
  )
  (wire (pts (xy 38.735 152.4) (xy 57.785 152.4))
    (stroke (width 0) (type default) (color 0 0 0 0))
  )
  (wire (pts (xy 45.085 76.2) (xy 57.785 76.2))
    (stroke (width 0) (type default) (color 0 0 0 0))
  )
  (wire (pts (xy 392.557 120.523) (xy 393.827 120.523))
    (stroke (width 0) (type default) (color 0 0 0 0))
  )
  (wire (pts (xy 207.645 107.95) (xy 194.31 107.95))
    (stroke (width 0) (type default) (color 0 0 0 0))
  )
  (polyline (pts (xy 38.735 104.14) (xy 37.465 104.14))
    (stroke (width 0) (type default) (color 0 0 0 0))
  )

  (wire (pts (xy 262.255 267.97) (xy 274.32 267.97))
    (stroke (width 0) (type default) (color 0 0 0 0))
  )
  (polyline (pts (xy 289.56 102.235) (xy 288.29 102.235))
    (stroke (width 0) (type default) (color 0 0 0 0))
  )

  (wire (pts (xy 194.945 41.91) (xy 207.645 41.91))
    (stroke (width 0) (type default) (color 0 0 0 0))
  )
  (polyline (pts (xy 288.29 141.986) (xy 288.29 137.033))
    (stroke (width 0) (type default) (color 0 0 0 0))
  )

  (wire (pts (xy 38.735 157.48) (xy 57.785 157.48))
    (stroke (width 0) (type default) (color 0 0 0 0))
  )
  (wire (pts (xy 155.956 248.666) (xy 155.956 251.206))
    (stroke (width 0) (type default) (color 0 0 0 0))
  )
  (polyline (pts (xy 287.02 157.353) (xy 288.29 157.353))
    (stroke (width 0) (type default) (color 0 0 0 0))
  )

  (wire (pts (xy 107.315 152.4) (xy 121.92 152.4))
    (stroke (width 0) (type default) (color 0 0 0 0))
  )
  (wire (pts (xy 45.085 83.82) (xy 57.785 83.82))
    (stroke (width 0) (type default) (color 0 0 0 0))
  )
  (wire (pts (xy 393.827 148.463) (xy 395.097 148.463))
    (stroke (width 0) (type default) (color 0 0 0 0))
  )
  (polyline (pts (xy 176.53 144.653) (xy 175.26 144.653))
    (stroke (width 0) (type default) (color 0 0 0 0))
  )

  (wire (pts (xy 120.015 93.98) (xy 107.315 93.98))
    (stroke (width 0) (type default) (color 0 0 0 0))
  )
  (polyline (pts (xy 177.8 100.965) (xy 177.8 97.155))
    (stroke (width 0) (type default) (color 0 0 0 0))
  )
  (polyline (pts (xy 123.825 109.855) (xy 123.825 95.377))
    (stroke (width 0) (type default) (color 0 0 0 0))
  )

  (wire (pts (xy 269.875 52.07) (xy 257.175 52.07))
    (stroke (width 0) (type default) (color 0 0 0 0))
  )
  (polyline (pts (xy 283.845 32.385) (xy 285.115 32.385))
    (stroke (width 0) (type default) (color 0 0 0 0))
  )

  (wire (pts (xy 198.755 194.31) (xy 207.645 194.31))
    (stroke (width 0) (type default) (color 0 0 0 0))
  )
  (wire (pts (xy 45.085 50.8) (xy 57.785 50.8))
    (stroke (width 0) (type default) (color 0 0 0 0))
  )
  (wire (pts (xy 120.015 81.28) (xy 107.315 81.28))
    (stroke (width 0) (type default) (color 0 0 0 0))
  )
  (wire (pts (xy 368.935 206.375) (xy 370.84 206.375))
    (stroke (width 0) (type default) (color 0 0 0 0))
  )
  (wire (pts (xy 207.645 156.21) (xy 191.262 156.21))
    (stroke (width 0) (type default) (color 0 0 0 0))
  )
  (wire (pts (xy 269.875 49.53) (xy 257.175 49.53))
    (stroke (width 0) (type default) (color 0 0 0 0))
  )
  (wire (pts (xy 269.875 166.37) (xy 257.175 166.37))
    (stroke (width 0) (type default) (color 0 0 0 0))
  )
  (polyline (pts (xy 28.575 169.545) (xy 29.845 169.545))
    (stroke (width 0) (type default) (color 0 0 0 0))
  )
  (polyline (pts (xy 179.07 51.181) (xy 179.705 51.181))
    (stroke (width 0) (type default) (color 0 0 0 0))
  )
  (polyline (pts (xy 37.465 122.555) (xy 37.465 131.445))
    (stroke (width 0) (type default) (color 0 0 0 0))
  )

  (wire (pts (xy 381.127 63.373) (xy 381.127 60.833))
    (stroke (width 0) (type default) (color 0 0 0 0))
  )
  (polyline (pts (xy 38.735 101.6) (xy 37.465 101.6))
    (stroke (width 0) (type default) (color 0 0 0 0))
  )
  (polyline (pts (xy 254 283.21) (xy 254 247.65))
    (stroke (width 0) (type default) (color 0 0 0 0))
  )

  (wire (pts (xy 45.085 142.24) (xy 57.785 142.24))
    (stroke (width 0) (type default) (color 0 0 0 0))
  )
  (wire (pts (xy 102.616 248.666) (xy 112.776 248.666))
    (stroke (width 0) (type default) (color 0 0 0 0))
  )
  (wire (pts (xy 207.645 62.23) (xy 194.945 62.23))
    (stroke (width 0) (type default) (color 0 0 0 0))
  )
  (wire (pts (xy 315.341 96.647) (xy 316.611 96.647))
    (stroke (width 0) (type default) (color 0 0 0 0))
  )
  (polyline (pts (xy 43.18 94.742) (xy 41.91 94.742))
    (stroke (width 0) (type default) (color 0 0 0 0))
  )

  (wire (pts (xy 386.08 181.61) (xy 387.985 181.61))
    (stroke (width 0) (type default) (color 0 0 0 0))
  )
  (polyline (pts (xy 28.575 174.625) (xy 28.575 178.435))
    (stroke (width 0) (type default) (color 0 0 0 0))
  )

  (wire (pts (xy 45.085 58.42) (xy 57.785 58.42))
    (stroke (width 0) (type default) (color 0 0 0 0))
  )
  (wire (pts (xy 316.23 171.45) (xy 316.23 172.72))
    (stroke (width 0) (type default) (color 0 0 0 0))
  )
  (wire (pts (xy 353.187 60.833) (xy 349.377 60.833))
    (stroke (width 0) (type default) (color 0 0 0 0))
  )
  (wire (pts (xy 392.557 63.373) (xy 393.827 63.373))
    (stroke (width 0) (type default) (color 0 0 0 0))
  )
  (polyline (pts (xy 181.102 40.894) (xy 182.372 40.894))
    (stroke (width 0) (type default) (color 0 0 0 0))
  )
  (polyline (pts (xy 287.02 141.986) (xy 288.29 141.986))
    (stroke (width 0) (type default) (color 0 0 0 0))
  )

  (wire (pts (xy 257.175 100.33) (xy 273.05 100.33))
    (stroke (width 0) (type default) (color 0 0 0 0))
  )
  (wire (pts (xy 257.175 125.73) (xy 274.2692 125.73))
    (stroke (width 0) (type default) (color 0 0 0 0))
  )
  (wire (pts (xy 269.875 107.95) (xy 257.175 107.95))
    (stroke (width 0) (type default) (color 0 0 0 0))
  )
  (polyline (pts (xy 177.8 31.115) (xy 179.07 31.115))
    (stroke (width 0) (type default) (color 0 0 0 0))
  )

  (wire (pts (xy 191.262 156.21) (xy 191.262 161.925))
    (stroke (width 0) (type default) (color 0 0 0 0))
  )
  (polyline (pts (xy 123.825 95.377) (xy 122.555 95.377))
    (stroke (width 0) (type default) (color 0 0 0 0))
  )

  (wire (pts (xy 112.776 248.666) (xy 122.936 248.666))
    (stroke (width 0) (type default) (color 0 0 0 0))
  )
  (wire (pts (xy 185.547 161.925) (xy 191.262 161.925))
    (stroke (width 0) (type default) (color 0 0 0 0))
  )
  (polyline (pts (xy 287.02 174.625) (xy 288.29 174.625))
    (stroke (width 0) (type default) (color 0 0 0 0))
  )

  (wire (pts (xy 96.901 248.666) (xy 99.314 248.666))
    (stroke (width 0) (type default) (color 0 0 0 0))
  )
  (wire (pts (xy 269.875 140.97) (xy 257.175 140.97))
    (stroke (width 0) (type default) (color 0 0 0 0))
  )
  (wire (pts (xy 120.015 91.44) (xy 107.315 91.44))
    (stroke (width 0) (type default) (color 0 0 0 0))
  )
  (wire (pts (xy 257.175 102.87) (xy 269.875 102.87))
    (stroke (width 0) (type default) (color 0 0 0 0))
  )
  (wire (pts (xy 269.875 57.15) (xy 257.175 57.15))
    (stroke (width 0) (type default) (color 0 0 0 0))
  )
  (wire (pts (xy 207.645 184.15) (xy 199.39 184.15))
    (stroke (width 0) (type default) (color 0 0 0 0))
  )
  (wire (pts (xy 194.945 140.97) (xy 207.645 140.97))
    (stroke (width 0) (type default) (color 0 0 0 0))
  )
  (wire (pts (xy 120.015 86.36) (xy 107.315 86.36))
    (stroke (width 0) (type default) (color 0 0 0 0))
  )
  (wire (pts (xy 33.655 160.02) (xy 57.785 160.02))
    (stroke (width 0) (type default) (color 0 0 0 0))
  )
  (wire (pts (xy 120.015 137.16) (xy 107.315 137.16))
    (stroke (width 0) (type default) (color 0 0 0 0))
  )
  (wire (pts (xy 45.085 55.88) (xy 57.785 55.88))
    (stroke (width 0) (type default) (color 0 0 0 0))
  )
  (wire (pts (xy 122.936 261.366) (xy 122.936 258.826))
    (stroke (width 0) (type default) (color 0 0 0 0))
  )
  (wire (pts (xy 107.315 99.06) (xy 120.015 99.06))
    (stroke (width 0) (type default) (color 0 0 0 0))
  )
  (wire (pts (xy 269.875 168.91) (xy 257.175 168.91))
    (stroke (width 0) (type default) (color 0 0 0 0))
  )
  (wire (pts (xy 316.611 96.647) (xy 316.611 99.187))
    (stroke (width 0) (type default) (color 0 0 0 0))
  )
  (polyline (pts (xy 287.02 161.925) (xy 288.29 161.925))
    (stroke (width 0) (type default) (color 0 0 0 0))
  )

  (wire (pts (xy 206.502 205.74) (xy 206.502 201.93))
    (stroke (width 0) (type default) (color 0 0 0 0))
  )
  (polyline (pts (xy 31.75 54.229) (xy 33.02 54.229))
    (stroke (width 0) (type default) (color 0 0 0 0))
  )
  (polyline (pts (xy 28.575 142.24) (xy 27.305 142.24))
    (stroke (width 0) (type default) (color 0 0 0 0))
  )

  (wire (pts (xy 257.175 130.81) (xy 274.2692 130.81))
    (stroke (width 0) (type default) (color 0 0 0 0))
  )
  (wire (pts (xy 38.735 154.94) (xy 57.785 154.94))
    (stroke (width 0) (type default) (color 0 0 0 0))
  )
  (wire (pts (xy 207.645 181.61) (xy 199.39 181.61))
    (stroke (width 0) (type default) (color 0 0 0 0))
  )
  (wire (pts (xy 269.875 39.37) (xy 257.175 39.37))
    (stroke (width 0) (type default) (color 0 0 0 0))
  )
  (polyline (pts (xy 179.07 70.993) (xy 179.07 51.181))
    (stroke (width 0) (type default) (color 0 0 0 0))
  )
  (polyline (pts (xy 254 247.65) (xy 300.355 247.65))
    (stroke (width 0) (type default) (color 0 0 0 0))
  )

  (wire (pts (xy 107.315 45.72) (xy 120.015 45.72))
    (stroke (width 0) (type default) (color 0 0 0 0))
  )
  (wire (pts (xy 45.085 40.64) (xy 57.785 40.64))
    (stroke (width 0) (type default) (color 0 0 0 0))
  )
  (wire (pts (xy 41.275 109.22) (xy 57.785 109.22))
    (stroke (width 0) (type default) (color 0 0 0 0))
  )
  (wire (pts (xy 195.072 138.43) (xy 207.645 138.43))
    (stroke (width 0) (type default) (color 0 0 0 0))
  )
  (wire (pts (xy 269.875 163.83) (xy 257.175 163.83))
    (stroke (width 0) (type default) (color 0 0 0 0))
  )
  (wire (pts (xy 387.985 181.61) (xy 387.985 182.88))
    (stroke (width 0) (type default) (color 0 0 0 0))
  )
  (wire (pts (xy 107.315 43.18) (xy 120.015 43.18))
    (stroke (width 0) (type default) (color 0 0 0 0))
  )
  (wire (pts (xy 382.397 92.583) (xy 381.127 92.583))
    (stroke (width 0) (type default) (color 0 0 0 0))
  )
  (polyline (pts (xy 137.16 154.305) (xy 138.43 154.305))
    (stroke (width 0) (type default) (color 0 0 0 0))
  )

  (wire (pts (xy 269.875 110.49) (xy 257.175 110.49))
    (stroke (width 0) (type default) (color 0 0 0 0))
  )
  (wire (pts (xy 41.275 129.54) (xy 57.785 129.54))
    (stroke (width 0) (type default) (color 0 0 0 0))
  )
  (wire (pts (xy 107.315 101.6) (xy 120.015 101.6))
    (stroke (width 0) (type default) (color 0 0 0 0))
  )
  (wire (pts (xy 45.085 177.8) (xy 57.785 177.8))
    (stroke (width 0) (type default) (color 0 0 0 0))
  )
  (wire (pts (xy 194.945 59.69) (xy 207.645 59.69))
    (stroke (width 0) (type default) (color 0 0 0 0))
  )
  (wire (pts (xy 120.015 48.26) (xy 107.315 48.26))
    (stroke (width 0) (type default) (color 0 0 0 0))
  )
  (wire (pts (xy 120.015 68.58) (xy 107.315 68.58))
    (stroke (width 0) (type default) (color 0 0 0 0))
  )
  (wire (pts (xy 257.175 82.55) (xy 273.05 82.55))
    (stroke (width 0) (type default) (color 0 0 0 0))
  )
  (wire (pts (xy 368.427 60.833) (xy 358.267 60.833))
    (stroke (width 0) (type default) (color 0 0 0 0))
  )
  (wire (pts (xy 45.085 68.58) (xy 57.785 68.58))
    (stroke (width 0) (type default) (color 0 0 0 0))
  )
  (wire (pts (xy 269.875 29.21) (xy 257.175 29.21))
    (stroke (width 0) (type default) (color 0 0 0 0))
  )
  (wire (pts (xy 107.315 132.08) (xy 120.015 132.08))
    (stroke (width 0) (type default) (color 0 0 0 0))
  )
  (wire (pts (xy 289.56 255.27) (xy 290.83 255.27))
    (stroke (width 0) (type default) (color 0 0 0 0))
  )
  (wire (pts (xy 395.097 145.923) (xy 395.097 148.463))
    (stroke (width 0) (type default) (color 0 0 0 0))
  )
  (polyline (pts (xy 123.825 94.615) (xy 123.825 85.217))
    (stroke (width 0) (type default) (color 0 0 0 0))
  )

  (wire (pts (xy 45.085 48.26) (xy 57.785 48.26))
    (stroke (width 0) (type default) (color 0 0 0 0))
  )
  (polyline (pts (xy 288.29 161.925) (xy 288.29 157.734))
    (stroke (width 0) (type default) (color 0 0 0 0))
  )

  (wire (pts (xy 45.085 33.02) (xy 57.785 33.02))
    (stroke (width 0) (type default) (color 0 0 0 0))
  )
  (wire (pts (xy 199.39 181.61) (xy 194.945 181.61))
    (stroke (width 0) (type default) (color 0 0 0 0))
  )
  (wire (pts (xy 45.085 78.74) (xy 57.785 78.74))
    (stroke (width 0) (type default) (color 0 0 0 0))
  )
  (wire (pts (xy 120.015 96.52) (xy 107.315 96.52))
    (stroke (width 0) (type default) (color 0 0 0 0))
  )
  (polyline (pts (xy 123.825 85.217) (xy 122.555 85.217))
    (stroke (width 0) (type default) (color 0 0 0 0))
  )

  (wire (pts (xy 207.645 100.33) (xy 194.945 100.33))
    (stroke (width 0) (type default) (color 0 0 0 0))
  )
  (polyline (pts (xy 137.795 28.575) (xy 139.065 28.575))
    (stroke (width 0) (type default) (color 0 0 0 0))
  )

  (wire (pts (xy 41.275 104.14) (xy 57.785 104.14))
    (stroke (width 0) (type default) (color 0 0 0 0))
  )
  (wire (pts (xy 107.315 144.78) (xy 121.92 144.78))
    (stroke (width 0) (type default) (color 0 0 0 0))
  )
  (wire (pts (xy 45.085 81.28) (xy 57.785 81.28))
    (stroke (width 0) (type default) (color 0 0 0 0))
  )
  (polyline (pts (xy 31.115 116.84) (xy 29.845 116.84))
    (stroke (width 0) (type default) (color 0 0 0 0))
  )

  (wire (pts (xy 269.875 36.83) (xy 257.175 36.83))
    (stroke (width 0) (type default) (color 0 0 0 0))
  )
  (wire (pts (xy 287.02 267.97) (xy 290.83 267.97))
    (stroke (width 0) (type default) (color 0 0 0 0))
  )
  (wire (pts (xy 368.427 90.043) (xy 358.267 90.043))
    (stroke (width 0) (type default) (color 0 0 0 0))
  )
  (polyline (pts (xy 125.095 111.125) (xy 122.428 111.125))
    (stroke (width 0) (type default) (color 0 0 0 0))
  )
  (polyline (pts (xy 37.465 131.445) (xy 38.735 131.445))
    (stroke (width 0) (type default) (color 0 0 0 0))
  )
  (polyline (pts (xy 288.29 174.625) (xy 288.29 170.18))
    (stroke (width 0) (type default) (color 0 0 0 0))
  )

  (wire (pts (xy 120.015 66.04) (xy 107.315 66.04))
    (stroke (width 0) (type default) (color 0 0 0 0))
  )
  (polyline (pts (xy 177.8 97.155) (xy 179.07 97.155))
    (stroke (width 0) (type default) (color 0 0 0 0))
  )

  (wire (pts (xy 386.08 206.375) (xy 387.35 206.375))
    (stroke (width 0) (type default) (color 0 0 0 0))
  )
  (wire (pts (xy 368.427 102.743) (xy 368.427 103.378))
    (stroke (width 0) (type default) (color 0 0 0 0))
  )
  (wire (pts (xy 99.314 247.269) (xy 99.314 248.666))
    (stroke (width 0) (type default) (color 0 0 0 0))
  )
  (polyline (pts (xy 133.477 84.836) (xy 134.747 84.836))
    (stroke (width 0) (type default) (color 0 0 0 0))
  )

  (wire (pts (xy 382.397 148.463) (xy 382.397 145.923))
    (stroke (width 0) (type default) (color 0 0 0 0))
  )
  (wire (pts (xy 134.366 256.286) (xy 134.366 258.826))
    (stroke (width 0) (type default) (color 0 0 0 0))
  )
  (wire (pts (xy 207.645 161.29) (xy 205.105 161.29))
    (stroke (width 0) (type default) (color 0 0 0 0))
  )
  (polyline (pts (xy 38.735 114.3) (xy 37.465 114.3))
    (stroke (width 0) (type default) (color 0 0 0 0))
  )
  (polyline (pts (xy 190.5 72.39) (xy 191.77 72.39))
    (stroke (width 0) (type default) (color 0 0 0 0))
  )

  (wire (pts (xy 207.645 135.89) (xy 194.945 135.89))
    (stroke (width 0) (type default) (color 0 0 0 0))
  )
  (wire (pts (xy 45.085 134.62) (xy 57.785 134.62))
    (stroke (width 0) (type default) (color 0 0 0 0))
  )
  (wire (pts (xy 257.175 196.85) (xy 277.495 196.85))
    (stroke (width 0) (type default) (color 0 0 0 0))
  )
  (polyline (pts (xy 31.75 160.02) (xy 30.48 160.02))
    (stroke (width 0) (type default) (color 0 0 0 0))
  )
  (polyline (pts (xy 285.115 76.581) (xy 283.337 76.581))
    (stroke (width 0) (type default) (color 0 0 0 0))
  )

  (wire (pts (xy 369.697 145.923) (xy 360.807 145.923))
    (stroke (width 0) (type default) (color 0 0 0 0))
  )
  (polyline (pts (xy 285.115 32.385) (xy 285.115 28.575))
    (stroke (width 0) (type default) (color 0 0 0 0))
  )

  (wire (pts (xy 379.73 216.535) (xy 367.665 216.535))
    (stroke (width 0) (type default) (color 0 0 0 0))
  )
  (wire (pts (xy 194.945 97.79) (xy 207.645 97.79))
    (stroke (width 0) (type default) (color 0 0 0 0))
  )
  (wire (pts (xy 381.127 117.983) (xy 382.397 117.983))
    (stroke (width 0) (type default) (color 0 0 0 0))
  )
  (wire (pts (xy 194.945 194.31) (xy 198.755 194.31))
    (stroke (width 0) (type default) (color 0 0 0 0))
  )
  (wire (pts (xy 269.875 41.91) (xy 257.175 41.91))
    (stroke (width 0) (type default) (color 0 0 0 0))
  )
  (wire (pts (xy 28.829 187.96) (xy 23.495 187.96))
    (stroke (width 0) (type default) (color 0 0 0 0))
  )
  (wire (pts (xy 368.427 73.533) (xy 368.427 74.168))
    (stroke (width 0) (type default) (color 0 0 0 0))
  )
  (wire (pts (xy 368.427 117.983) (xy 368.427 119.253))
    (stroke (width 0) (type default) (color 0 0 0 0))
  )
  (polyline (pts (xy 285.115 97.282) (xy 285.115 76.581))
    (stroke (width 0) (type default) (color 0 0 0 0))
  )
  (polyline (pts (xy 284.988 67.437) (xy 283.718 67.437))
    (stroke (width 0) (type default) (color 0 0 0 0))
  )
  (polyline (pts (xy 139.065 51.816) (xy 137.795 51.816))
    (stroke (width 0) (type default) (color 0 0 0 0))
  )
  (polyline (pts (xy 29.845 173.355) (xy 28.575 173.355))
    (stroke (width 0) (type default) (color 0 0 0 0))
  )
  (polyline (pts (xy 283.337 76.2) (xy 285.115 76.2))
    (stroke (width 0) (type default) (color 0 0 0 0))
  )

  (wire (pts (xy 107.315 78.74) (xy 120.015 78.74))
    (stroke (width 0) (type default) (color 0 0 0 0))
  )
  (polyline (pts (xy 138.43 154.305) (xy 138.43 143.51))
    (stroke (width 0) (type default) (color 0 0 0 0))
  )

  (wire (pts (xy 194.945 92.71) (xy 207.645 92.71))
    (stroke (width 0) (type default) (color 0 0 0 0))
  )
  (polyline (pts (xy 284.988 66.548) (xy 283.718 66.548))
    (stroke (width 0) (type default) (color 0 0 0 0))
  )

  (wire (pts (xy 290.83 191.77) (xy 306.07 191.77))
    (stroke (width 0) (type default) (color 0 0 0 0))
  )
  (wire (pts (xy 257.175 176.53) (xy 285.75 176.53))
    (stroke (width 0) (type default) (color 0 0 0 0))
  )
  (wire (pts (xy 207.645 102.87) (xy 194.945 102.87))
    (stroke (width 0) (type default) (color 0 0 0 0))
  )
  (wire (pts (xy 120.015 76.2) (xy 107.315 76.2))
    (stroke (width 0) (type default) (color 0 0 0 0))
  )
  (wire (pts (xy 45.085 170.18) (xy 57.785 170.18))
    (stroke (width 0) (type default) (color 0 0 0 0))
  )
  (wire (pts (xy 45.085 66.04) (xy 57.785 66.04))
    (stroke (width 0) (type default) (color 0 0 0 0))
  )
  (polyline (pts (xy 121.285 119.38) (xy 122.555 119.38))
    (stroke (width 0) (type default) (color 0 0 0 0))
  )
  (polyline (pts (xy 175.26 134.874) (xy 176.53 134.874))
    (stroke (width 0) (type default) (color 0 0 0 0))
  )

  (wire (pts (xy 382.397 120.523) (xy 381.127 120.523))
    (stroke (width 0) (type default) (color 0 0 0 0))
  )
  (wire (pts (xy 181.102 161.925) (xy 185.547 161.925))
    (stroke (width 0) (type default) (color 0 0 0 0))
  )
  (polyline (pts (xy 288.29 137.033) (xy 287.02 137.033))
    (stroke (width 0) (type default) (color 0 0 0 0))
  )

  (wire (pts (xy 199.39 184.15) (xy 194.945 184.15))
    (stroke (width 0) (type default) (color 0 0 0 0))
  )
  (wire (pts (xy 386.715 232.41) (xy 387.985 232.41))
    (stroke (width 0) (type default) (color 0 0 0 0))
  )
  (wire (pts (xy 107.315 109.22) (xy 120.015 109.22))
    (stroke (width 0) (type default) (color 0 0 0 0))
  )
  (wire (pts (xy 257.175 95.25) (xy 273.05 95.25))
    (stroke (width 0) (type default) (color 0 0 0 0))
  )
  (wire (pts (xy 269.875 113.03) (xy 257.175 113.03))
    (stroke (width 0) (type default) (color 0 0 0 0))
  )
  (wire (pts (xy 120.015 167.64) (xy 116.84 167.64))
    (stroke (width 0) (type default) (color 0 0 0 0))
  )
  (wire (pts (xy 392.557 92.583) (xy 393.827 92.583))
    (stroke (width 0) (type default) (color 0 0 0 0))
  )
  (wire (pts (xy 382.397 145.923) (xy 383.667 145.923))
    (stroke (width 0) (type default) (color 0 0 0 0))
  )
  (wire (pts (xy 107.315 167.64) (xy 116.84 167.64))
    (stroke (width 0) (type default) (color 0 0 0 0))
  )
  (wire (pts (xy 257.175 194.31) (xy 277.495 194.31))
    (stroke (width 0) (type default) (color 0 0 0 0))
  )
  (wire (pts (xy 120.015 71.12) (xy 107.315 71.12))
    (stroke (width 0) (type default) (color 0 0 0 0))
  )
  (wire (pts (xy 45.085 71.12) (xy 57.785 71.12))
    (stroke (width 0) (type default) (color 0 0 0 0))
  )
  (wire (pts (xy 207.645 113.03) (xy 194.945 113.03))
    (stroke (width 0) (type default) (color 0 0 0 0))
  )
  (wire (pts (xy 369.57 181.61) (xy 371.475 181.61))
    (stroke (width 0) (type default) (color 0 0 0 0))
  )
  (wire (pts (xy 353.187 90.043) (xy 349.377 90.043))
    (stroke (width 0) (type default) (color 0 0 0 0))
  )
  (wire (pts (xy 257.175 120.65) (xy 274.2692 120.65))
    (stroke (width 0) (type default) (color 0 0 0 0))
  )
  (wire (pts (xy 382.397 145.923) (xy 369.697 145.923))
    (stroke (width 0) (type default) (color 0 0 0 0))
  )
  (wire (pts (xy 315.341 109.347) (xy 324.739 109.347))
    (stroke (width 0) (type default) (color 0 0 0 0))
  )
  (wire (pts (xy 269.875 171.45) (xy 257.175 171.45))
    (stroke (width 0) (type default) (color 0 0 0 0))
  )
  (wire (pts (xy 349.377 117.983) (xy 353.187 117.983))
    (stroke (width 0) (type default) (color 0 0 0 0))
  )
  (polyline (pts (xy 179.705 70.993) (xy 179.07 70.993))
    (stroke (width 0) (type default) (color 0 0 0 0))
  )

  (text "Ethernet" (at 139.7 136.525 0)
    (effects (font (size 1.27 1.27)) (justify left bottom))
  )
  (text "USB-C\nhost mode" (at 26.035 140.97 180)
    (effects (font (size 1.27 1.27)) (justify right bottom))
  )
  (text "CAM 0" (at 26.035 135.89 180)
    (effects (font (size 1.27 1.27)) (justify right bottom))
  )
  (text "USB-C\nhost mode" (at 177.165 116.205 180)
    (effects (font (size 1.27 1.27)) (justify right bottom))
  )
  (text "not used" (at 125.984 115.189 0)
    (effects (font (size 1.27 1.27)) (justify left bottom))
  )
  (text "USB-C\nDP mode" (at 288.925 161.925 0)
    (effects (font (size 1.27 1.27)) (justify left bottom))
  )
  (text "CSI3 \nnot used" (at 124.587 104.394 0)
    (effects (font (size 1.27 1.27)) (justify left bottom))
  )
  (text "USB-C\nDP mode" (at 288.925 174.625 0)
    (effects (font (size 1.27 1.27)) (justify left bottom))
  )
  (text "HDMI" (at 290.83 114.3 0)
    (effects (font (size 1.27 1.27)) (justify left bottom))
  )
  (text "CAM 1" (at 27.94 177.165 180)
    (effects (font (size 1.27 1.27)) (justify right bottom))
  )
  (text "USB-C\ndebug" (at 288.925 169.545 0)
    (effects (font (size 1.27 1.27)) (justify left bottom))
  )
  (text "not used" (at 286.258 68.072 0)
    (effects (font (size 1.27 1.27)) (justify left bottom))
  )
  (text "CSI2 \nnot used" (at 31.75 88.265 0)
    (effects (font (size 1.27 1.27)) (justify left bottom))
  )
  (text "USB-C\nhost mode" (at 179.451 81.915 180)
    (effects (font (size 1.27 1.27)) (justify right bottom))
  )
  (text "not used" (at 28.575 104.775 0)
    (effects (font (size 1.27 1.27)) (justify left bottom))
  )
  (text "Comment:\n4.0V - 15V Input OR \n5V output\nCharging power\ninput.\nPower output for\nOTG device.\nUSB/adaptor\ninsertion detect"
    (at 166.497 212.598 0)
    (effects (font (size 1.27 1.27)) (justify left bottom))
  )
  (text "not used" (at 27.94 120.015 0)
    (effects (font (size 1.27 1.27)) (justify left bottom))
  )
  (text "SoM Module" (at 338.455 21.59 0)
    (effects (font (size 2.0066 2.0066) (thickness 0.4013) bold) (justify left bottom))
  )
  (text "RTC battery" (at 310.515 168.275 0)
    (effects (font (size 2.0066 2.0066) (thickness 0.4013) bold) (justify left bottom))
  )
  (text "CAM 1" (at 25.4 143.51 180)
    (effects (font (size 1.27 1.27)) (justify right bottom))
  )
  (text "CAM 0" (at 27.94 172.72 180)
    (effects (font (size 1.27 1.27)) (justify right bottom))
  )
  (text "CAM 1" (at 24.13 71.12 0)
    (effects (font (size 1.27 1.27)) (justify left bottom))
  )
  (text "not used" (at 29.21 154.94 180)
    (effects (font (size 1.27 1.27)) (justify right bottom))
  )
  (text "RaspberryPi \ncompatible \nconnector" (at 167.005 61.595 0)
    (effects (font (size 1.27 1.27)) (justify left bottom))
  )
  (text "USB-C\nDP mode" (at 285.75 32.385 0)
    (effects (font (size 1.27 1.27)) (justify left bottom))
  )
  (text "CAM 0" (at 24.13 48.26 0)
    (effects (font (size 1.27 1.27)) (justify left bottom))
  )
  (text "HDMI" (at 177.165 34.29 180)
    (effects (font (size 1.27 1.27)) (justify right bottom))
  )
  (text "RTC battery" (at 288.925 164.465 0)
    (effects (font (size 1.27 1.27)) (justify left bottom))
  )
  (text "not used" (at 182.88 40.005 0)
    (effects (font (size 1.27 1.27)) (justify left bottom))
  )
  (text "not used" (at 288.925 177.165 0)
    (effects (font (size 1.27 1.27)) (justify left bottom))
  )
  (text "NVMe" (at 140.335 44.45 0)
    (effects (font (size 1.27 1.27)) (justify left bottom))
  )
  (text "not used" (at 189.865 75.565 180)
    (effects (font (size 1.27 1.27)) (justify right bottom))
  )
  (text "SoM" (at 13.335 17.78 0)
    (effects (font (size 2.9972 2.9972) (thickness 0.5994) bold) (justify left bottom))
  )
  (text "not used" (at 36.195 128.905 180)
    (effects (font (size 1.27 1.27)) (justify right bottom))
  )
  (text "User buttons" (at 338.582 48.768 0)
    (effects (font (size 2.0066 2.0066) (thickness 0.4013) bold) (justify left bottom))
  )
  (text "CSI2 cont" (at 124.46 92.456 0)
    (effects (font (size 1.27 1.27)) (justify left bottom))
  )
  (text "USB-C\nhost mode" (at 289.052 141.351 0)
    (effects (font (size 1.27 1.27)) (justify left bottom))
  )
  (text "USB-C\nDP mode" (at 174.625 152.4 180)
    (effects (font (size 1.27 1.27)) (justify right bottom))
  )
  (text "Auto ON and recovery mode\nselection" (at 255.27 255.27 0)
    (effects (font (size 2.0066 2.0066) (thickness 0.4013) bold) (justify left bottom))
  )
  (text "HDMI" (at 286.004 54.991 0)
    (effects (font (size 1.27 1.27)) (justify left bottom))
  )
  (text "not used" (at 182.88 37.465 0)
    (effects (font (size 1.27 1.27)) (justify left bottom))
  )
  (text "Comment:\n2.95V @800mA\nSD card power supply" (at 132.08 174.625 0)
    (effects (font (size 1.27 1.27)) (justify left bottom))
  )
  (text "Comment:\n1.8V @300mA\nPower supply for\nIOVDD of cameras"
    (at 132.08 165.1 0)
    (effects (font (size 1.27 1.27)) (justify left bottom))
  )
  (text "not used" (at 278.5364 125.4506 0)
    (effects (font (size 1.27 1.27)) (justify left bottom))
  )
  (text "not used" (at 123.825 66.675 0)
    (effects (font (size 1.27 1.27)) (justify left bottom))
  )
  (text "SD card" (at 135.382 77.597 0)
    (effects (font (size 1.27 1.27)) (justify left bottom))
  )
  (text "I2C10 pullups" (at 303.911 93.472 0)
    (effects (font (size 2.0066 2.0066) (thickness 0.4013) bold) (justify left bottom))
  )
  (text "USB-C\nhost mode" (at 174.625 139.7 180)
    (effects (font (size 1.27 1.27)) (justify right bottom))
  )
  (text "USB-C\nDP mode" (at 289.052 151.638 0)
    (effects (font (size 1.27 1.27)) (justify left bottom))
  )
  (text "not used" (at 28.575 114.935 0)
    (effects (font (size 1.27 1.27)) (justify left bottom))
  )
  (text "I2C\npin header" (at 290.195 106.045 0)
    (effects (font (size 1.27 1.27)) (justify left bottom))
  )
  (text "not used" (at 123.19 120.015 0)
    (effects (font (size 1.27 1.27)) (justify left bottom))
  )
  (text "HDMI" (at 177.165 100.33 180)
    (effects (font (size 1.27 1.27)) (justify right bottom))
  )
  (text "not used" (at 286.258 73.152 0)
    (effects (font (size 1.27 1.27)) (justify left bottom))
  )
  (text "not used" (at 139.7 149.225 0)
    (effects (font (size 1.27 1.27)) (justify left bottom))
  )
  (text "not used" (at 28.575 110.49 0)
    (effects (font (size 1.27 1.27)) (justify left bottom))
  )
  (text "Comment:\n1.8V @2A\nPower supply for external GPIO’s\npull-up circuit and level shift circuit"
    (at 154.051 168.529 0)
    (effects (font (size 1.27 1.27)) (justify left bottom))
  )
  (text "Comment:\n3.0V @600mA\nPower supply for\nsensors" (at 166.37 192.405 0)
    (effects (font (size 1.27 1.27)) (justify left bottom))
  )
  (text "Comment:\n1.8V @100mA\nPower supply for\nIOVDD or VDD of sensors"
    (at 166.37 179.705 0)
    (effects (font (size 1.27 1.27)) (justify left bottom))
  )
  (text "HDMI" (at 36.195 107.95 180)
    (effects (font (size 1.27 1.27)) (justify right bottom))
  )
  (text "CAM 0" (at 29.21 117.475 180)
    (effects (font (size 1.27 1.27)) (justify right bottom))
  )
  (text "not used" (at 285.623 87.757 0)
    (effects (font (size 1.27 1.27)) (justify left bottom))
  )
  (text "Comment:\nPower supply for the module\n3.55V - 4.4V INPUT, 3.8 nominal\nMust be provided with sufficient\ncurrent of up to 3 A"
    (at 48.641 199.644 180)
    (effects (font (size 1.27 1.27)) (justify right bottom))
  )
  (text "Comment:\nPower rails from connectors 3&4 of SOM:\nLDO12A_1V8   : 1.8V @300mA (low power mode charger)\nLDO14A_1V88: 1.8V @50mA (Power supply for IOVDD of TP and LCDs)\nLDO24A_3V075: 3.075V @150mA (Power supply for DP’s pull-up circuits.\nLDO28A_3V0 :3.0V@150mA (Power supply for VDD of TP)\n"
    (at 94.615 283.21 0)
    (effects (font (size 1.27 1.27)) (justify left bottom))
  )
  (text "4 lane DSI \nconnector" (at 167.894 46.228 0)
    (effects (font (size 1.27 1.27)) (justify left bottom))
  )
  (text "not used" (at 28.575 102.235 0)
    (effects (font (size 1.27 1.27)) (justify left bottom))
  )
  (text "not used" (at 28.575 112.395 0)
    (effects (font (size 1.27 1.27)) (justify left bottom))
  )

  (label "CAM1_DVDD_EN" (at 57.785 154.94 180)
    (effects (font (size 1.27 1.27)) (justify right bottom))
  )
  (label "GYRO_INT" (at 107.315 149.86 0)
    (effects (font (size 1.27 1.27)) (justify left bottom))
  )
  (label "LT6911_RST" (at 57.785 106.68 180)
    (effects (font (size 1.27 1.27)) (justify right bottom))
  )
  (label "MAG_DRDY_INT" (at 107.315 147.32 0)
    (effects (font (size 1.27 1.27)) (justify left bottom))
  )
  (label "CAM1_MCLK" (at 107.315 114.3 0)
    (effects (font (size 1.27 1.27)) (justify left bottom))
  )
  (label "CODEC_INT2" (at 257.2004 125.73 0)
    (effects (font (size 1.27 1.27)) (justify left bottom))
  )
  (label "I2S3_DATA0" (at 257.175 95.25 0)
    (effects (font (size 1.27 1.27)) (justify left bottom))
  )
  (label "SLIMBUS_CLK" (at 257.175 74.93 0)
    (effects (font (size 1.27 1.27)) (justify left bottom))
  )
  (label "USER_LED" (at 368.3 242.57 0)
    (effects (font (size 1.27 1.27)) (justify left bottom))
  )
  (label "I2S2_DATA0" (at 257.175 82.55 0)
    (effects (font (size 1.27 1.27)) (justify left bottom))
  )
  (label "TP_INT" (at 207.645 72.39 180)
    (effects (font (size 1.27 1.27)) (justify right bottom))
  )
  (label "USER_LED" (at 185.42 29.21 0)
    (effects (font (size 1.27 1.27)) (justify left bottom))
  )
  (label "I2S2_WS" (at 257.175 77.47 0)
    (effects (font (size 1.27 1.27)) (justify left bottom))
  )
  (label "CSI3_LN1_P" (at 107.315 96.52 0)
    (effects (font (size 1.27 1.27)) (justify left bottom))
  )
  (label "I2S2_SCK" (at 257.175 80.01 0)
    (effects (font (size 1.27 1.27)) (justify left bottom))
  )
  (label "VOL_UP_R" (at 378.587 90.043 180)
    (effects (font (size 1.27 1.27)) (justify right bottom))
  )
  (label "CAM3_RST" (at 57.785 149.86 180)
    (effects (font (size 1.27 1.27)) (justify right bottom))
  )
  (label "TP_RST" (at 207.645 74.93 180)
    (effects (font (size 1.27 1.27)) (justify right bottom))
  )
  (label "CAM0_AFVDD_EN" (at 57.785 101.6 180)
    (effects (font (size 1.27 1.27)) (justify right bottom))
  )
  (label "HOME_KEY_R" (at 378.587 60.833 180)
    (effects (font (size 1.27 1.27)) (justify right bottom))
  )
  (label "VBAT_SOM" (at 36.195 187.96 0)
    (effects (font (size 1.27 1.27)) (justify left bottom))
  )
  (label "LCM_VDD_EN" (at 107.315 66.04 0)
    (effects (font (size 1.27 1.27)) (justify left bottom))
  )
  (label "CODEC_SPI_MISO" (at 257.2004 120.65 0)
    (effects (font (size 1.27 1.27)) (justify left bottom))
  )
  (label "CAM0_MCLK" (at 107.315 111.76 0)
    (effects (font (size 1.27 1.27)) (justify left bottom))
  )
  (label "CAM0_AVDD_EN" (at 57.785 119.38 180)
    (effects (font (size 1.27 1.27)) (justify right bottom))
  )
  (label "CAM1_AVDD_EN" (at 57.785 114.3 180)
    (effects (font (size 1.27 1.27)) (justify right bottom))
  )
  (label "CAM3_TRIGGER_OUT" (at 57.785 152.4 180)
    (effects (font (size 1.27 1.27)) (justify right bottom))
  )
  (label "CSI2_LN0_P" (at 107.315 91.44 0)
    (effects (font (size 1.27 1.27)) (justify left bottom))
  )
  (label "WCD_CLK" (at 257.175 67.31 0)
    (effects (font (size 1.27 1.27)) (justify left bottom))
  )
  (label "CSI3_LN0_P" (at 107.315 101.6 0)
    (effects (font (size 1.27 1.27)) (justify left bottom))
  )
  (label "CAM0_DVDD_EN" (at 57.785 157.48 180)
    (effects (font (size 1.27 1.27)) (justify right bottom))
  )
  (label "CSI2_LN3_N" (at 57.785 93.98 180)
    (effects (font (size 1.27 1.27)) (justify right bottom))
  )
  (label "CODEC_INT1" (at 257.2004 123.19 0)
    (effects (font (size 1.27 1.27)) (justify left bottom))
  )
  (label "CSI3_CLK_P" (at 107.315 106.68 0)
    (effects (font (size 1.27 1.27)) (justify left bottom))
  )
  (label "PWR_R" (at 378.587 117.983 180)
    (effects (font (size 1.27 1.27)) (justify right bottom))
  )
  (label "VRTC" (at 310.515 171.45 0)
    (effects (font (size 1.27 1.27)) (justify left bottom))
  )
  (label "CSI2_LN2_P" (at 57.785 86.36 180)
    (effects (font (size 1.27 1.27)) (justify right bottom))
  )
  (label "BOOT" (at 367.665 216.535 0)
    (effects (font (size 1.27 1.27)) (justify left bottom))
  )
  (label "PWR_OFF" (at 57.785 147.32 180)
    (effects (font (size 1.27 1.27)) (justify right bottom))
  )
  (label "HDMI1_INTO" (at 57.785 109.22 180)
    (effects (font (size 1.27 1.27)) (justify right bottom))
  )
  (label "AUTO_ON_N" (at 262.255 267.97 0)
    (effects (font (size 1.27 1.27)) (justify left bottom))
  )
  (label "CSI3_LN1_N" (at 107.315 99.06 0)
    (effects (font (size 1.27 1.27)) (justify left bottom))
  )
  (label "VBAT_SOM" (at 306.07 191.77 180)
    (effects (font (size 1.27 1.27)) (justify right bottom))
  )
  (label "CSI2_CLK_P" (at 107.315 86.36 0)
    (effects (font (size 1.27 1.27)) (justify left bottom))
  )
  (label "MAG_INT" (at 107.315 144.78 0)
    (effects (font (size 1.27 1.27)) (justify left bottom))
  )
  (label "USB_BOOT" (at 192.786 158.75 0)
    (effects (font (size 1.27 1.27)) (justify left bottom))
  )
  (label "CSI3_CLK_N" (at 107.315 109.22 0)
    (effects (font (size 1.27 1.27)) (justify left bottom))
  )
  (label "SSC_I2C1_SDA" (at 207.645 36.83 180)
    (effects (font (size 1.27 1.27)) (justify right bottom))
  )
  (label "BOOT" (at 193.04 167.005 0)
    (effects (font (size 1.27 1.27)) (justify left bottom))
  )
  (label "ACCL_INT" (at 107.315 152.4 0)
    (effects (font (size 1.27 1.27)) (justify left bottom))
  )
  (label "VBAT_SOM" (at 83.566 248.666 0)
    (effects (font (size 1.27 1.27)) (justify left bottom))
  )
  (label "I2S2_DATA1" (at 257.175 85.09 0)
    (effects (font (size 1.27 1.27)) (justify left bottom))
  )
  (label "CAM3_VCC_EN" (at 57.785 127 180)
    (effects (font (size 1.27 1.27)) (justify right bottom))
  )
  (label "CSI2_LN0_N" (at 107.315 93.98 0)
    (effects (font (size 1.27 1.27)) (justify left bottom))
  )
  (label "CSI3_LN0_N" (at 107.315 104.14 0)
    (effects (font (size 1.27 1.27)) (justify left bottom))
  )
  (label "VRTC" (at 269.875 163.83 180)
    (effects (font (size 1.27 1.27)) (justify right bottom))
  )
  (label "CSI2_LN3_P" (at 57.785 91.44 180)
    (effects (font (size 1.27 1.27)) (justify right bottom))
  )
  (label "RESET_USBHUB" (at 57.785 129.54 180)
    (effects (font (size 1.27 1.27)) (justify right bottom))
  )
  (label "CSI2_LN2_N" (at 57.785 88.9 180)
    (effects (font (size 1.27 1.27)) (justify right bottom))
  )
  (label "CSI2_CLK_N" (at 107.315 88.9 0)
    (effects (font (size 1.27 1.27)) (justify left bottom))
  )
  (label "AUTO_ON_N" (at 33.655 160.02 0)
    (effects (font (size 1.27 1.27)) (justify left bottom))
  )
  (label "LT6911_3V3_EN" (at 57.785 124.46 180)
    (effects (font (size 1.27 1.27)) (justify right bottom))
  )
  (label "SLIMBUS_DATA0" (at 257.175 69.85 0)
    (effects (font (size 1.27 1.27)) (justify left bottom))
  )
  (label "CAM1_AFVDD_EN" (at 57.785 104.14 180)
    (effects (font (size 1.27 1.27)) (justify right bottom))
  )
  (label "VOL_DOWN_R" (at 380.492 145.923 180)
    (effects (font (size 1.27 1.27)) (justify right bottom))
  )
  (label "SLIMBUS_DATA1" (at 257.175 72.39 0)
    (effects (font (size 1.27 1.27)) (justify left bottom))
  )
  (label "CSI2_LN1_P" (at 57.785 81.28 180)
    (effects (font (size 1.27 1.27)) (justify right bottom))
  )
  (label "ETH_3V3_EN" (at 257.2004 130.81 0)
    (effects (font (size 1.27 1.27)) (justify left bottom))
  )
  (label "SSC_I2C1_SCL" (at 207.645 39.37 180)
    (effects (font (size 1.27 1.27)) (justify right bottom))
  )
  (label "CAM3_MCLK" (at 107.315 119.38 0)
    (effects (font (size 1.27 1.27)) (justify left bottom))
  )
  (label "CSI2_LN1_N" (at 57.785 83.82 180)
    (effects (font (size 1.27 1.27)) (justify right bottom))
  )
  (label "I2S3_SCK" (at 257.175 100.33 0)
    (effects (font (size 1.27 1.27)) (justify left bottom))
  )
  (label "I2S3_WS" (at 257.175 87.63 0)
    (effects (font (size 1.27 1.27)) (justify left bottom))
  )
  (label "CAM3_TRIGGER_IN" (at 257.2004 128.27 0)
    (effects (font (size 1.27 1.27)) (justify left bottom))
  )
  (label "USB_BOOT" (at 262.255 265.43 0)
    (effects (font (size 1.27 1.27)) (justify left bottom))
  )
  (label "CAM1_RST" (at 57.785 111.76 180)
    (effects (font (size 1.27 1.27)) (justify right bottom))
  )

  (global_label "PCIE1_TX_N" (shape output) (at 120.015 139.7 0) (fields_autoplaced)
    (effects (font (size 1.27 1.27)) (justify left))
    (property "Intersheet References" "${INTERSHEET_REFS}" (id 0) (at 2.54 -48.895 0)
      (effects (font (size 1.27 1.27)) hide)
    )
  )
  (global_label "SD_CMD" (shape input) (at 120.015 71.12 0) (fields_autoplaced)
    (effects (font (size 1.27 1.27)) (justify left))
    (property "Intersheet References" "${INTERSHEET_REFS}" (id 0) (at 2.54 -15.875 0)
      (effects (font (size 1.27 1.27)) hide)
    )
  )
  (global_label "I2S1_DATA0" (shape output) (at 269.875 118.11 0) (fields_autoplaced)
    (effects (font (size 1.27 1.27)) (justify left))
    (property "Intersheet References" "${INTERSHEET_REFS}" (id 0) (at 10.16 -19.05 0)
      (effects (font (size 1.27 1.27)) hide)
    )
  )
  (global_label "DSI0_CLK_N" (shape output) (at 194.945 54.61 180) (fields_autoplaced)
    (effects (font (size 1.27 1.27)) (justify right))
    (property "Intersheet References" "${INTERSHEET_REFS}" (id 0) (at 2.54 -3.81 0)
      (effects (font (size 1.27 1.27)) hide)
    )
  )
  (global_label "I2C10_SCL" (shape output) (at 269.875 102.87 0) (fields_autoplaced)
    (effects (font (size 1.27 1.27)) (justify left))
    (property "Intersheet References" "${INTERSHEET_REFS}" (id 0) (at 10.16 -19.05 0)
      (effects (font (size 1.27 1.27)) hide)
    )
  )
  (global_label "CSI0_LN3_P" (shape input) (at 45.085 30.48 180) (fields_autoplaced)
    (effects (font (size 1.27 1.27)) (justify right))
    (property "Intersheet References" "${INTERSHEET_REFS}" (id 0) (at -5.08 -0.635 0)
      (effects (font (size 1.27 1.27)) hide)
    )
  )
  (global_label "VOL_DOWN" (shape input) (at 349.377 145.923 180) (fields_autoplaced)
    (effects (font (size 1.27 1.27)) (justify right))
    (property "Intersheet References" "${INTERSHEET_REFS}" (id 0) (at -10.668 -2.032 0)
      (effects (font (size 1.27 1.27)) hide)
    )
  )
  (global_label "5V_SYS" (shape input) (at 369.57 181.61 180) (fields_autoplaced)
    (effects (font (size 1.27 1.27)) (justify right))
    (property "Intersheet References" "${INTERSHEET_REFS}" (id 0) (at 0 -2.54 0)
      (effects (font (size 1.27 1.27)) hide)
    )
  )
  (global_label "DSI0_LN2_P" (shape output) (at 194.945 46.99 180) (fields_autoplaced)
    (effects (font (size 1.27 1.27)) (justify right))
    (property "Intersheet References" "${INTERSHEET_REFS}" (id 0) (at 2.54 -6.35 0)
      (effects (font (size 1.27 1.27)) hide)
    )
  )
  (global_label "I2C10_SDA" (shape bidirectional) (at 315.341 106.807 180) (fields_autoplaced)
    (effects (font (size 1.27 1.27)) (justify right))
    (property "Intersheet References" "${INTERSHEET_REFS}" (id 0) (at 11.811 -15.113 0)
      (effects (font (size 1.27 1.27)) hide)
    )
  )
  (global_label "LVS1A_1V8" (shape output) (at 120.015 165.1 0) (fields_autoplaced)
    (effects (font (size 1.27 1.27)) (justify left))
    (property "Intersheet References" "${INTERSHEET_REFS}" (id 0) (at 2.54 -51.435 0)
      (effects (font (size 1.27 1.27)) hide)
    )
  )
  (global_label "PCIE0_TX_P" (shape output) (at 120.015 40.64 0) (fields_autoplaced)
    (effects (font (size 1.27 1.27)) (justify left))
    (property "Intersheet References" "${INTERSHEET_REFS}" (id 0) (at 2.54 -0.635 0)
      (effects (font (size 1.27 1.27)) hide)
    )
  )
  (global_label "DSI0_LN0_N" (shape output) (at 194.945 64.77 180) (fields_autoplaced)
    (effects (font (size 1.27 1.27)) (justify right))
    (property "Intersheet References" "${INTERSHEET_REFS}" (id 0) (at 2.54 -8.89 0)
      (effects (font (size 1.27 1.27)) hide)
    )
  )
  (global_label "DSI0_LN0_P" (shape output) (at 194.945 62.23 180) (fields_autoplaced)
    (effects (font (size 1.27 1.27)) (justify right))
    (property "Intersheet References" "${INTERSHEET_REFS}" (id 0) (at 2.54 -13.97 0)
      (effects (font (size 1.27 1.27)) hide)
    )
  )
  (global_label "STUSB4500_ATTACH" (shape input) (at 194.945 105.41 180) (fields_autoplaced)
    (effects (font (size 1.27 1.27)) (justify right))
    (property "Intersheet References" "${INTERSHEET_REFS}" (id 0) (at 2.54 -13.97 0)
      (effects (font (size 1.27 1.27)) hide)
    )
  )
  (global_label "STUSB4500_GPIO" (shape input) (at 194.945 102.87 180) (fields_autoplaced)
    (effects (font (size 1.27 1.27)) (justify right))
    (property "Intersheet References" "${INTERSHEET_REFS}" (id 0) (at 2.54 -13.97 0)
      (effects (font (size 1.27 1.27)) hide)
    )
  )
  (global_label "CSI1_LN3_P" (shape input) (at 45.085 55.88 180) (fields_autoplaced)
    (effects (font (size 1.27 1.27)) (justify right))
    (property "Intersheet References" "${INTERSHEET_REFS}" (id 0) (at -5.08 -15.875 0)
      (effects (font (size 1.27 1.27)) hide)
    )
  )
  (global_label "CSI1_LN2_N" (shape input) (at 45.085 63.5 180) (fields_autoplaced)
    (effects (font (size 1.27 1.27)) (justify right))
    (property "Intersheet References" "${INTERSHEET_REFS}" (id 0) (at -5.08 -15.875 0)
      (effects (font (size 1.27 1.27)) hide)
    )
  )
  (global_label "CSI0_CLK_N" (shape input) (at 45.085 53.34 180) (fields_autoplaced)
    (effects (font (size 1.27 1.27)) (justify right))
    (property "Intersheet References" "${INTERSHEET_REFS}" (id 0) (at -5.08 -10.795 0)
      (effects (font (size 1.27 1.27)) hide)
    )
  )
  (global_label "5V_SYS" (shape input) (at 369.57 232.41 180) (fields_autoplaced)
    (effects (font (size 1.27 1.27)) (justify right))
    (property "Intersheet References" "${INTERSHEET_REFS}" (id 0) (at 0 0 0)
      (effects (font (size 1.27 1.27)) hide)
    )
  )
  (global_label "PCIE1_WAKE_N" (shape input) (at 120.015 127 0) (fields_autoplaced)
    (effects (font (size 1.27 1.27)) (justify left))
    (property "Intersheet References" "${INTERSHEET_REFS}" (id 0) (at 2.54 -41.275 0)
      (effects (font (size 1.27 1.27)) hide)
    )
  )
  (global_label "PCIE0_TX_N" (shape output) (at 120.015 38.1 0) (fields_autoplaced)
    (effects (font (size 1.27 1.27)) (justify left))
    (property "Intersheet References" "${INTERSHEET_REFS}" (id 0) (at 2.54 -0.635 0)
      (effects (font (size 1.27 1.27)) hide)
    )
  )
  (global_label "USB_PD_DISABLE" (shape input) (at 194.31 107.95 180) (fields_autoplaced)
    (effects (font (size 1.27 1.27)) (justify right))
    (property "Intersheet References" "${INTERSHEET_REFS}" (id 0) (at 2.54 -13.97 0)
      (effects (font (size 1.27 1.27)) hide)
    )
  )
  (global_label "USB1_SS_RX1_N" (shape input) (at 194.945 148.59 180) (fields_autoplaced)
    (effects (font (size 1.27 1.27)) (justify right))
    (property "Intersheet References" "${INTERSHEET_REFS}" (id 0) (at 2.54 -21.59 0)
      (effects (font (size 1.27 1.27)) hide)
    )
  )
  (global_label "CCI0_I2C_SDA" (shape input) (at 45.085 172.72 180) (fields_autoplaced)
    (effects (font (size 1.27 1.27)) (justify right))
    (property "Intersheet References" "${INTERSHEET_REFS}" (id 0) (at -5.08 -36.195 0)
      (effects (font (size 1.27 1.27)) hide)
    )
  )
  (global_label "PCIE1_RX_P" (shape input) (at 120.015 129.54 0) (fields_autoplaced)
    (effects (font (size 1.27 1.27)) (justify left))
    (property "Intersheet References" "${INTERSHEET_REFS}" (id 0) (at 2.54 -43.815 0)
      (effects (font (size 1.27 1.27)) hide)
    )
  )
  (global_label "PCIE0_WAKE_N" (shape input) (at 120.015 33.02 0) (fields_autoplaced)
    (effects (font (size 1.27 1.27)) (justify left))
    (property "Intersheet References" "${INTERSHEET_REFS}" (id 0) (at 2.54 1.905 0)
      (effects (font (size 1.27 1.27)) hide)
    )
  )
  (global_label "CSI0_LN0_P" (shape input) (at 45.085 45.72 180) (fields_autoplaced)
    (effects (font (size 1.27 1.27)) (justify right))
    (property "Intersheet References" "${INTERSHEET_REFS}" (id 0) (at -5.08 -10.795 0)
      (effects (font (size 1.27 1.27)) hide)
    )
  )
  (global_label "5V_SYS" (shape input) (at 368.935 206.375 180) (fields_autoplaced)
    (effects (font (size 1.27 1.27)) (justify right))
    (property "Intersheet References" "${INTERSHEET_REFS}" (id 0) (at 0 0 0)
      (effects (font (size 1.27 1.27)) hide)
    )
  )
  (global_label "USB2_SS_RX_N" (shape input) (at 195.072 138.43 180) (fields_autoplaced)
    (effects (font (size 1.27 1.27)) (justify right))
    (property "Intersheet References" "${INTERSHEET_REFS}" (id 0) (at 2.667 -13.97 0)
      (effects (font (size 1.27 1.27)) hide)
    )
  )
  (global_label "VREG_S4A_1V8" (shape input) (at 315.341 96.647 180) (fields_autoplaced)
    (effects (font (size 1.27 1.27)) (justify right))
    (property "Intersheet References" "${INTERSHEET_REFS}" (id 0) (at 11.811 -15.113 0)
      (effects (font (size 1.27 1.27)) hide)
    )
  )
  (global_label "DSI1_LN1_N" (shape output) (at 269.875 64.77 0) (fields_autoplaced)
    (effects (font (size 1.27 1.27)) (justify left))
    (property "Intersheet References" "${INTERSHEET_REFS}" (id 0) (at 10.16 -8.89 0)
      (effects (font (size 1.27 1.27)) hide)
    )
  )
  (global_label "PWRKEY" (shape input) (at 349.377 117.983 180) (fields_autoplaced)
    (effects (font (size 1.27 1.27)) (justify right))
    (property "Intersheet References" "${INTERSHEET_REFS}" (id 0) (at -10.668 -2.032 0)
      (effects (font (size 1.27 1.27)) hide)
    )
  )
  (global_label "USB1_SS_TX0_P" (shape output) (at 269.875 153.67 0) (fields_autoplaced)
    (effects (font (size 1.27 1.27)) (justify left))
    (property "Intersheet References" "${INTERSHEET_REFS}" (id 0) (at 10.16 -31.75 0)
      (effects (font (size 1.27 1.27)) hide)
    )
  )
  (global_label "SD_DATA3" (shape input) (at 120.015 81.28 0) (fields_autoplaced)
    (effects (font (size 1.27 1.27)) (justify left))
    (property "Intersheet References" "${INTERSHEET_REFS}" (id 0) (at 2.54 -15.875 0)
      (effects (font (size 1.27 1.27)) hide)
    )
  )
  (global_label "CSI1_LN1_P" (shape input) (at 45.085 66.04 180) (fields_autoplaced)
    (effects (font (size 1.27 1.27)) (justify right))
    (property "Intersheet References" "${INTERSHEET_REFS}" (id 0) (at -5.08 -20.955 0)
      (effects (font (size 1.27 1.27)) hide)
    )
  )
  (global_label "3V3_SYS_EN" (shape output) (at 205.105 163.83 180) (fields_autoplaced)
    (effects (font (size 1.27 1.27)) (justify right))
    (property "Intersheet References" "${INTERSHEET_REFS}" (id 0) (at 12.7 -31.75 0)
      (effects (font (size 1.27 1.27)) hide)
    )
  )
  (global_label "PCIE0_REFCLK_N" (shape output) (at 120.015 45.72 0) (fields_autoplaced)
    (effects (font (size 1.27 1.27)) (justify left))
    (property "Intersheet References" "${INTERSHEET_REFS}" (id 0) (at 2.54 -3.175 0)
      (effects (font (size 1.27 1.27)) hide)
    )
  )
  (global_label "3V8_SYS" (shape input) (at 23.495 187.96 180) (fields_autoplaced)
    (effects (font (size 1.27 1.27)) (justify right))
    (property "Intersheet References" "${INTERSHEET_REFS}" (id 0) (at -5.08 -41.275 0)
      (effects (font (size 1.27 1.27)) hide)
    )
  )
  (global_label "USB2_SS_TX_P" (shape output) (at 194.945 140.97 180) (fields_autoplaced)
    (effects (font (size 1.27 1.27)) (justify right))
    (property "Intersheet References" "${INTERSHEET_REFS}" (id 0) (at 2.54 -19.05 0)
      (effects (font (size 1.27 1.27)) hide)
    )
  )
  (global_label "I2C4_SCL" (shape output) (at 194.945 34.29 180) (fields_autoplaced)
    (effects (font (size 1.27 1.27)) (justify right))
    (property "Intersheet References" "${INTERSHEET_REFS}" (id 0) (at 2.54 1.27 0)
      (effects (font (size 1.27 1.27)) hide)
    )
  )
  (global_label "USB2_SS_RX_P" (shape input) (at 194.945 135.89 180) (fields_autoplaced)
    (effects (font (size 1.27 1.27)) (justify right))
    (property "Intersheet References" "${INTERSHEET_REFS}" (id 0) (at 2.54 -19.05 0)
      (effects (font (size 1.27 1.27)) hide)
    )
  )
  (global_label "USB2C_HS_D_P" (shape bidirectional) (at 269.875 138.43 0) (fields_autoplaced)
    (effects (font (size 1.27 1.27)) (justify left))
    (property "Intersheet References" "${INTERSHEET_REFS}" (id 0) (at 10.16 -21.59 0)
      (effects (font (size 1.27 1.27)) hide)
    )
  )
  (global_label "HOME_KEY" (shape input) (at 269.875 179.07 0) (fields_autoplaced)
    (effects (font (size 1.27 1.27)) (justify left))
    (property "Intersheet References" "${INTERSHEET_REFS}" (id 0) (at 10.16 -31.75 0)
      (effects (font (size 1.27 1.27)) hide)
    )
  )
  (global_label "USB_CC1" (shape bidirectional) (at 269.875 173.99 0) (fields_autoplaced)
    (effects (font (size 1.27 1.27)) (justify left))
    (property "Intersheet References" "${INTERSHEET_REFS}" (id 0) (at 10.16 -31.75 0)
      (effects (font (size 1.27 1.27)) hide)
    )
  )
  (global_label "DSI1_LN3_N" (shape output) (at 269.875 59.69 0) (fields_autoplaced)
    (effects (font (size 1.27 1.27)) (justify left))
    (property "Intersheet References" "${INTERSHEET_REFS}" (id 0) (at 10.16 -6.35 0)
      (effects (font (size 1.27 1.27)) hide)
    )
  )
  (global_label "DSI0_LN1_P" (shape output) (at 194.945 57.15 180) (fields_autoplaced)
    (effects (font (size 1.27 1.27)) (justify right))
    (property "Intersheet References" "${INTERSHEET_REFS}" (id 0) (at 2.54 -11.43 0)
      (effects (font (size 1.27 1.27)) hide)
    )
  )
  (global_label "USB_VBUS" (shape input) (at 194.945 194.31 180) (fields_autoplaced)
    (effects (font (size 1.27 1.27)) (justify right))
    (property "Intersheet References" "${INTERSHEET_REFS}" (id 0) (at 2.54 -34.29 0)
      (effects (font (size 1.27 1.27)) hide)
    )
  )
  (global_label "I2S1_SCK" (shape output) (at 269.875 113.03 0) (fields_autoplaced)
    (effects (font (size 1.27 1.27)) (justify left))
    (property "Intersheet References" "${INTERSHEET_REFS}" (id 0) (at 10.16 -19.05 0)
      (effects (font (size 1.27 1.27)) hide)
    )
  )
  (global_label "USB1_SS_RX0_P" (shape input) (at 194.945 151.13 180) (fields_autoplaced)
    (effects (font (size 1.27 1.27)) (justify right))
    (property "Intersheet References" "${INTERSHEET_REFS}" (id 0) (at 2.54 -26.67 0)
      (effects (font (size 1.27 1.27)) hide)
    )
  )
  (global_label "LT9611_GPIO5" (shape output) (at 194.945 97.79 180) (fields_autoplaced)
    (effects (font (size 1.27 1.27)) (justify right))
    (property "Intersheet References" "${INTERSHEET_REFS}" (id 0) (at 2.54 -13.97 0)
      (effects (font (size 1.27 1.27)) hide)
    )
  )
  (global_label "SBU_SW_OE" (shape output) (at 269.875 29.21 0) (fields_autoplaced)
    (effects (font (size 1.27 1.27)) (justify left))
    (property "Intersheet References" "${INTERSHEET_REFS}" (id 0) (at 10.16 1.27 0)
      (effects (font (size 1.27 1.27)) hide)
    )
  )
  (global_label "CSI0_LN2_N" (shape input) (at 45.085 38.1 180) (fields_autoplaced)
    (effects (font (size 1.27 1.27)) (justify right))
    (property "Intersheet References" "${INTERSHEET_REFS}" (id 0) (at -5.08 -0.635 0)
      (effects (font (size 1.27 1.27)) hide)
    )
  )
  (global_label "CSI0_CLK_P" (shape input) (at 45.085 50.8 180) (fields_autoplaced)
    (effects (font (size 1.27 1.27)) (justify right))
    (property "Intersheet References" "${INTERSHEET_REFS}" (id 0) (at -5.08 -10.795 0)
      (effects (font (size 1.27 1.27)) hide)
    )
  )
  (global_label "SD_DATA2" (shape input) (at 120.015 83.82 0) (fields_autoplaced)
    (effects (font (size 1.27 1.27)) (justify left))
    (property "Intersheet References" "${INTERSHEET_REFS}" (id 0) (at 2.54 -15.875 0)
      (effects (font (size 1.27 1.27)) hide)
    )
  )
  (global_label "USB_CC2" (shape bidirectional) (at 269.875 171.45 0) (fields_autoplaced)
    (effects (font (size 1.27 1.27)) (justify left))
    (property "Intersheet References" "${INTERSHEET_REFS}" (id 0) (at 10.16 -31.75 0)
      (effects (font (size 1.27 1.27)) hide)
    )
  )
  (global_label "DSI0_CLK_P" (shape output) (at 194.945 52.07 180) (fields_autoplaced)
    (effects (font (size 1.27 1.27)) (justify right))
    (property "Intersheet References" "${INTERSHEET_REFS}" (id 0) (at 2.54 -8.89 0)
      (effects (font (size 1.27 1.27)) hide)
    )
  )
  (global_label "USB2_FAULT" (shape input) (at 45.085 139.7 180) (fields_autoplaced)
    (effects (font (size 1.27 1.27)) (justify right))
    (property "Intersheet References" "${INTERSHEET_REFS}" (id 0) (at -5.08 -36.195 0)
      (effects (font (size 1.27 1.27)) hide)
    )
  )
  (global_label "VREG_S4A_1V8" (shape input) (at 368.3 191.77 180) (fields_autoplaced)
    (effects (font (size 1.27 1.27)) (justify right))
    (property "Intersheet References" "${INTERSHEET_REFS}" (id 0) (at 0 -1.27 0)
      (effects (font (size 1.27 1.27)) hide)
    )
  )
  (global_label "VOL_DOWN" (shape input) (at 269.875 36.83 0) (fields_autoplaced)
    (effects (font (size 1.27 1.27)) (justify left))
    (property "Intersheet References" "${INTERSHEET_REFS}" (id 0) (at 10.16 1.27 0)
      (effects (font (size 1.27 1.27)) hide)
    )
  )
  (global_label "LVS2A_1V8" (shape output) (at 194.945 181.61 180) (fields_autoplaced)
    (effects (font (size 1.27 1.27)) (justify right))
    (property "Intersheet References" "${INTERSHEET_REFS}" (id 0) (at 2.54 -31.75 0)
      (effects (font (size 1.27 1.27)) hide)
    )
  )
  (global_label "VREG_S4A_1V8" (shape input) (at 289.56 255.27 180) (fields_autoplaced)
    (effects (font (size 1.27 1.27)) (justify right))
    (property "Intersheet References" "${INTERSHEET_REFS}" (id 0) (at 0 0 0)
      (effects (font (size 1.27 1.27)) hide)
    )
  )
  (global_label "CSI0_LN1_N" (shape input) (at 45.085 43.18 180) (fields_autoplaced)
    (effects (font (size 1.27 1.27)) (justify right))
    (property "Intersheet References" "${INTERSHEET_REFS}" (id 0) (at -5.08 -3.175 0)
      (effects (font (size 1.27 1.27)) hide)
    )
  )
  (global_label "I2C4_SDA" (shape bidirectional) (at 194.945 31.75 180) (fields_autoplaced)
    (effects (font (size 1.27 1.27)) (justify right))
    (property "Intersheet References" "${INTERSHEET_REFS}" (id 0) (at 2.54 1.27 0)
      (effects (font (size 1.27 1.27)) hide)
    )
  )
  (global_label "PCIE1_RX_N" (shape input) (at 120.015 132.08 0) (fields_autoplaced)
    (effects (font (size 1.27 1.27)) (justify left))
    (property "Intersheet References" "${INTERSHEET_REFS}" (id 0) (at 2.54 -43.815 0)
      (effects (font (size 1.27 1.27)) hide)
    )
  )
  (global_label "USB2_SINK" (shape input) (at 194.945 113.03 180) (fields_autoplaced)
    (effects (font (size 1.27 1.27)) (justify right))
    (property "Intersheet References" "${INTERSHEET_REFS}" (id 0) (at 2.54 -13.97 0)
      (effects (font (size 1.27 1.27)) hide)
    )
  )
  (global_label "DSI0_LN3_N" (shape output) (at 194.945 44.45 180) (fields_autoplaced)
    (effects (font (size 1.27 1.27)) (justify right))
    (property "Intersheet References" "${INTERSHEET_REFS}" (id 0) (at 2.54 1.27 0)
      (effects (font (size 1.27 1.27)) hide)
    )
  )
  (global_label "USB1_D_P" (shape bidirectional) (at 269.875 148.59 0) (fields_autoplaced)
    (effects (font (size 1.27 1.27)) (justify left))
    (property "Intersheet References" "${INTERSHEET_REFS}" (id 0) (at 10.16 -29.21 0)
      (effects (font (size 1.27 1.27)) hide)
    )
  )
  (global_label "LDO19A_3V0" (shape output) (at 194.945 184.15 180) (fields_autoplaced)
    (effects (font (size 1.27 1.27)) (justify right))
    (property "Intersheet References" "${INTERSHEET_REFS}" (id 0) (at 2.54 -31.75 0)
      (effects (font (size 1.27 1.27)) hide)
    )
  )
  (global_label "STUSB4500_AB_SIDE" (shape input) (at 194.945 95.25 180) (fields_autoplaced)
    (effects (font (size 1.27 1.27)) (justify right))
    (property "Intersheet References" "${INTERSHEET_REFS}" (id 0) (at 2.54 -13.97 0)
      (effects (font (size 1.27 1.27)) hide)
    )
  )
  (global_label "CSI1_LN0_P" (shape input) (at 45.085 71.12 180) (fields_autoplaced)
    (effects (font (size 1.27 1.27)) (justify right))
    (property "Intersheet References" "${INTERSHEET_REFS}" (id 0) (at -5.08 -23.495 0)
      (effects (font (size 1.27 1.27)) hide)
    )
  )
  (global_label "PCIE0_RX_P" (shape input) (at 120.015 48.26 0) (fields_autoplaced)
    (effects (font (size 1.27 1.27)) (justify left))
    (property "Intersheet References" "${INTERSHEET_REFS}" (id 0) (at 2.54 -5.715 0)
      (effects (font (size 1.27 1.27)) hide)
    )
  )
  (global_label "STUSB4500_ALERT" (shape input) (at 194.945 92.71 180) (fields_autoplaced)
    (effects (font (size 1.27 1.27)) (justify right))
    (property "Intersheet References" "${INTERSHEET_REFS}" (id 0) (at 2.54 -13.97 0)
      (effects (font (size 1.27 1.27)) hide)
    )
  )
  (global_label "PWRKEY" (shape input) (at 269.875 34.29 0) (fields_autoplaced)
    (effects (font (size 1.27 1.27)) (justify left))
    (property "Intersheet References" "${INTERSHEET_REFS}" (id 0) (at 10.16 1.27 0)
      (effects (font (size 1.27 1.27)) hide)
    )
  )
  (global_label "SD_DATA1" (shape input) (at 120.015 78.74 0) (fields_autoplaced)
    (effects (font (size 1.27 1.27)) (justify left))
    (property "Intersheet References" "${INTERSHEET_REFS}" (id 0) (at 2.54 -15.875 0)
      (effects (font (size 1.27 1.27)) hide)
    )
  )
  (global_label "CSI0_LN1_P" (shape input) (at 45.085 40.64 180) (fields_autoplaced)
    (effects (font (size 1.27 1.27)) (justify right))
    (property "Intersheet References" "${INTERSHEET_REFS}" (id 0) (at -5.08 -8.255 0)
      (effects (font (size 1.27 1.27)) hide)
    )
  )
  (global_label "DSI1_LN0_P" (shape output) (at 269.875 41.91 0) (fields_autoplaced)
    (effects (font (size 1.27 1.27)) (justify left))
    (property "Intersheet References" "${INTERSHEET_REFS}" (id 0) (at 10.16 -3.81 0)
      (effects (font (size 1.27 1.27)) hide)
    )
  )
  (global_label "EDP_AUX_P" (shape bidirectional) (at 269.875 158.75 0) (fields_autoplaced)
    (effects (font (size 1.27 1.27)) (justify left))
    (property "Intersheet References" "${INTERSHEET_REFS}" (id 0) (at 10.16 -31.75 0)
      (effects (font (size 1.27 1.27)) hide)
    )
  )
  (global_label "VOL_UP" (shape input) (at 349.377 90.043 180) (fields_autoplaced)
    (effects (font (size 1.27 1.27)) (justify right))
    (property "Intersheet References" "${INTERSHEET_REFS}" (id 0) (at -10.668 -2.032 0)
      (effects (font (size 1.27 1.27)) hide)
    )
  )
  (global_label "DSI0_LN3_P" (shape output) (at 194.945 41.91 180) (fields_autoplaced)
    (effects (font (size 1.27 1.27)) (justify right))
    (property "Intersheet References" "${INTERSHEET_REFS}" (id 0) (at 2.54 -3.81 0)
      (effects (font (size 1.27 1.27)) hide)
    )
  )
  (global_label "SBU_SW_SEL" (shape output) (at 269.875 31.75 0) (fields_autoplaced)
    (effects (font (size 1.27 1.27)) (justify left))
    (property "Intersheet References" "${INTERSHEET_REFS}" (id 0) (at 10.16 1.27 0)
      (effects (font (size 1.27 1.27)) hide)
    )
  )
  (global_label "PCIE0_REFCLK_P" (shape output) (at 120.015 43.18 0) (fields_autoplaced)
    (effects (font (size 1.27 1.27)) (justify left))
    (property "Intersheet References" "${INTERSHEET_REFS}" (id 0) (at 2.54 -3.175 0)
      (effects (font (size 1.27 1.27)) hide)
    )
  )
  (global_label "PCIE1_REFCLK_P" (shape output) (at 120.015 134.62 0) (fields_autoplaced)
    (effects (font (size 1.27 1.27)) (justify left))
    (property "Intersheet References" "${INTERSHEET_REFS}" (id 0) (at 2.54 -46.355 0)
      (effects (font (size 1.27 1.27)) hide)
    )
  )
  (global_label "CSI0_LN2_P" (shape input) (at 45.085 35.56 180) (fields_autoplaced)
    (effects (font (size 1.27 1.27)) (justify right))
    (property "Intersheet References" "${INTERSHEET_REFS}" (id 0) (at -5.08 -5.715 0)
      (effects (font (size 1.27 1.27)) hide)
    )
  )
  (global_label "DSI1_LN2_P" (shape output) (at 269.875 52.07 0) (fields_autoplaced)
    (effects (font (size 1.27 1.27)) (justify left))
    (property "Intersheet References" "${INTERSHEET_REFS}" (id 0) (at 10.16 -6.35 0)
      (effects (font (size 1.27 1.27)) hide)
    )
  )
  (global_label "USB2_EN" (shape output) (at 194.945 80.01 180) (fields_autoplaced)
    (effects (font (size 1.27 1.27)) (justify right))
    (property "Intersheet References" "${INTERSHEET_REFS}" (id 0) (at 2.54 -13.97 0)
      (effects (font (size 1.27 1.27)) hide)
    )
  )
  (global_label "PCIE1_REFCLK_N" (shape output) (at 120.015 137.16 0) (fields_autoplaced)
    (effects (font (size 1.27 1.27)) (justify left))
    (property "Intersheet References" "${INTERSHEET_REFS}" (id 0) (at 2.54 -46.355 0)
      (effects (font (size 1.27 1.27)) hide)
    )
  )
  (global_label "DSI0_LN1_N" (shape output) (at 194.945 59.69 180) (fields_autoplaced)
    (effects (font (size 1.27 1.27)) (justify right))
    (property "Intersheet References" "${INTERSHEET_REFS}" (id 0) (at 2.54 -6.35 0)
      (effects (font (size 1.27 1.27)) hide)
    )
  )
  (global_label "I2C10_SCL" (shape input) (at 315.341 109.347 180) (fields_autoplaced)
    (effects (font (size 1.27 1.27)) (justify right))
    (property "Intersheet References" "${INTERSHEET_REFS}" (id 0) (at 11.811 -15.113 0)
      (effects (font (size 1.27 1.27)) hide)
    )
  )
  (global_label "HOME_KEY" (shape input) (at 349.377 60.833 180) (fields_autoplaced)
    (effects (font (size 1.27 1.27)) (justify right))
    (property "Intersheet References" "${INTERSHEET_REFS}" (id 0) (at -10.668 -2.032 0)
      (effects (font (size 1.27 1.27)) hide)
    )
  )
  (global_label "USB1_SS_TX1_N" (shape output) (at 269.875 146.05 0) (fields_autoplaced)
    (effects (font (size 1.27 1.27)) (justify left))
    (property "Intersheet References" "${INTERSHEET_REFS}" (id 0) (at 10.16 -21.59 0)
      (effects (font (size 1.27 1.27)) hide)
    )
  )
  (global_label "CAM0_RST" (shape output) (at 45.085 116.84 180) (fields_autoplaced)
    (effects (font (size 1.27 1.27)) (justify right))
    (property "Intersheet References" "${INTERSHEET_REFS}" (id 0) (at -5.08 -36.195 0)
      (effects (font (size 1.27 1.27)) hide)
    )
  )
  (global_label "1V2_SYS_EN" (shape output) (at 205.105 161.29 180) (fields_autoplaced)
    (effects (font (size 1.27 1.27)) (justify right))
    (property "Intersheet References" "${INTERSHEET_REFS}" (id 0) (at 12.7 -31.75 0)
      (effects (font (size 1.27 1.27)) hide)
    )
  )
  (global_label "USB2C_HS_D_N" (shape bidirectional) (at 269.875 140.97 0) (fields_autoplaced)
    (effects (font (size 1.27 1.27)) (justify left))
    (property "Intersheet References" "${INTERSHEET_REFS}" (id 0) (at 10.16 -21.59 0)
      (effects (font (size 1.27 1.27)) hide)
    )
  )
  (global_label "CSI0_LN3_N" (shape input) (at 45.085 33.02 180) (fields_autoplaced)
    (effects (font (size 1.27 1.27)) (justify right))
    (property "Intersheet References" "${INTERSHEET_REFS}" (id 0) (at -5.08 -0.635 0)
      (effects (font (size 1.27 1.27)) hide)
    )
  )
  (global_label "PCIE0_RST_N" (shape output) (at 120.015 30.48 0) (fields_autoplaced)
    (effects (font (size 1.27 1.27)) (justify left))
    (property "Intersheet References" "${INTERSHEET_REFS}" (id 0) (at 2.54 1.905 0)
      (effects (font (size 1.27 1.27)) hide)
    )
  )
  (global_label "LT9611_RST" (shape output) (at 194.945 100.33 180) (fields_autoplaced)
    (effects (font (size 1.27 1.27)) (justify right))
    (property "Intersheet References" "${INTERSHEET_REFS}" (id 0) (at 2.54 -13.97 0)
      (effects (font (size 1.27 1.27)) hide)
    )
  )
  (global_label "CSI1_CLK_N" (shape input) (at 45.085 78.74 180) (fields_autoplaced)
    (effects (font (size 1.27 1.27)) (justify right))
    (property "Intersheet References" "${INTERSHEET_REFS}" (id 0) (at -5.08 -20.955 0)
      (effects (font (size 1.27 1.27)) hide)
    )
  )
  (global_label "CSI1_LN2_P" (shape input) (at 45.085 60.96 180) (fields_autoplaced)
    (effects (font (size 1.27 1.27)) (justify right))
    (property "Intersheet References" "${INTERSHEET_REFS}" (id 0) (at -5.08 -15.875 0)
      (effects (font (size 1.27 1.27)) hide)
    )
  )
  (global_label "SD_DET" (shape input) (at 120.015 73.66 0) (fields_autoplaced)
    (effects (font (size 1.27 1.27)) (justify left))
    (property "Intersheet References" "${INTERSHEET_REFS}" (id 0) (at 2.54 -15.875 0)
      (effects (font (size 1.27 1.27)) hide)
    )
  )
  (global_label "USB1_D_N" (shape bidirectional) (at 269.875 151.13 0) (fields_autoplaced)
    (effects (font (size 1.27 1.27)) (justify left))
    (property "Intersheet References" "${INTERSHEET_REFS}" (id 0) (at 10.16 -24.13 0)
      (effects (font (size 1.27 1.27)) hide)
    )
  )
  (global_label "DSI1_LN0_N" (shape output) (at 269.875 44.45 0) (fields_autoplaced)
    (effects (font (size 1.27 1.27)) (justify left))
    (property "Intersheet References" "${INTERSHEET_REFS}" (id 0) (at 10.16 1.27 0)
      (effects (font (size 1.27 1.27)) hide)
    )
  )
  (global_label "PCIE0_RX_N" (shape input) (at 120.015 50.8 0) (fields_autoplaced)
    (effects (font (size 1.27 1.27)) (justify left))
    (property "Intersheet References" "${INTERSHEET_REFS}" (id 0) (at 2.54 -5.715 0)
      (effects (font (size 1.27 1.27)) hide)
    )
  )
  (global_label "PCIE1_TX_P" (shape output) (at 120.015 142.24 0) (fields_autoplaced)
    (effects (font (size 1.27 1.27)) (justify left))
    (property "Intersheet References" "${INTERSHEET_REFS}" (id 0) (at 2.54 -48.895 0)
      (effects (font (size 1.27 1.27)) hide)
    )
  )
  (global_label "CSI1_CLK_P" (shape input) (at 45.085 76.2 180) (fields_autoplaced)
    (effects (font (size 1.27 1.27)) (justify right))
    (property "Intersheet References" "${INTERSHEET_REFS}" (id 0) (at -5.08 -26.035 0)
      (effects (font (size 1.27 1.27)) hide)
    )
  )
  (global_label "TP_I2C_SCL" (shape output) (at 194.945 67.31 180) (fields_autoplaced)
    (effects (font (size 1.27 1.27)) (justify right))
    (property "Intersheet References" "${INTERSHEET_REFS}" (id 0) (at 2.54 -13.97 0)
      (effects (font (size 1.27 1.27)) hide)
    )
  )
  (global_label "PCIE0_CLKREQ_N" (shape input) (at 120.015 35.56 0) (fields_autoplaced)
    (effects (font (size 1.27 1.27)) (justify left))
    (property "Intersheet References" "${INTERSHEET_REFS}" (id 0) (at 2.54 1.905 0)
      (effects (font (size 1.27 1.27)) hide)
    )
  )
  (global_label "DSI1_CLK_P" (shape output) (at 269.875 46.99 0) (fields_autoplaced)
    (effects (font (size 1.27 1.27)) (justify left))
    (property "Intersheet References" "${INTERSHEET_REFS}" (id 0) (at 10.16 -3.81 0)
      (effects (font (size 1.27 1.27)) hide)
    )
  )
  (global_label "VOL_UP" (shape input) (at 269.875 39.37 0) (fields_autoplaced)
    (effects (font (size 1.27 1.27)) (justify left))
    (property "Intersheet References" "${INTERSHEET_REFS}" (id 0) (at 10.16 1.27 0)
      (effects (font (size 1.27 1.27)) hide)
    )
  )
  (global_label "TP_I2C_SDA" (shape bidirectional) (at 194.945 69.85 180) (fields_autoplaced)
    (effects (font (size 1.27 1.27)) (justify right))
    (property "Intersheet References" "${INTERSHEET_REFS}" (id 0) (at 2.54 -13.97 0)
      (effects (font (size 1.27 1.27)) hide)
    )
  )
  (global_label "CAM1_PWDN" (shape output) (at 45.085 142.24 180) (fields_autoplaced)
    (effects (font (size 1.27 1.27)) (justify right))
    (property "Intersheet References" "${INTERSHEET_REFS}" (id 0) (at -5.08 -36.195 0)
      (effects (font (size 1.27 1.27)) hide)
    )
  )
  (global_label "I2S1_MCLK" (shape output) (at 269.875 110.49 0) (fields_autoplaced)
    (effects (font (size 1.27 1.27)) (justify left))
    (property "Intersheet References" "${INTERSHEET_REFS}" (id 0) (at 10.16 -19.05 0)
      (effects (font (size 1.27 1.27)) hide)
    )
  )
  (global_label "EDP_AUX_N" (shape bidirectional) (at 269.875 161.29 0) (fields_autoplaced)
    (effects (font (size 1.27 1.27)) (justify left))
    (property "Intersheet References" "${INTERSHEET_REFS}" (id 0) (at 10.16 -31.75 0)
      (effects (font (size 1.27 1.27)) hide)
    )
  )
  (global_label "DBG_TXD" (shape output) (at 269.875 168.91 0) (fields_autoplaced)
    (effects (font (size 1.27 1.27)) (justify left))
    (property "Intersheet References" "${INTERSHEET_REFS}" (id 0) (at 10.16 -31.75 0)
      (effects (font (size 1.27 1.27)) hide)
    )
  )
  (global_label "CSI1_LN0_N" (shape input) (at 45.085 73.66 180) (fields_autoplaced)
    (effects (font (size 1.27 1.27)) (justify right))
    (property "Intersheet References" "${INTERSHEET_REFS}" (id 0) (at -5.08 -18.415 0)
      (effects (font (size 1.27 1.27)) hide)
    )
  )
  (global_label "PCIE1_RST_N" (shape output) (at 120.015 121.92 0) (fields_autoplaced)
    (effects (font (size 1.27 1.27)) (justify left))
    (property "Intersheet References" "${INTERSHEET_REFS}" (id 0) (at 2.54 -41.275 0)
      (effects (font (size 1.27 1.27)) hide)
    )
  )
  (global_label "SD_DATA0" (shape input) (at 120.015 76.2 0) (fields_autoplaced)
    (effects (font (size 1.27 1.27)) (justify left))
    (property "Intersheet References" "${INTERSHEET_REFS}" (id 0) (at 2.54 -15.875 0)
      (effects (font (size 1.27 1.27)) hide)
    )
  )
  (global_label "CCI1_I2C_SCL" (shape input) (at 45.085 177.8 180) (fields_autoplaced)
    (effects (font (size 1.27 1.27)) (justify right))
    (property "Intersheet References" "${INTERSHEET_REFS}" (id 0) (at -5.08 -36.195 0)
      (effects (font (size 1.27 1.27)) hide)
    )
  )
  (global_label "I2C10_SDA" (shape bidirectional) (at 269.875 105.41 0) (fields_autoplaced)
    (effects (font (size 1.27 1.27)) (justify left))
    (property "Intersheet References" "${INTERSHEET_REFS}" (id 0) (at 10.16 -19.05 0)
      (effects (font (size 1.27 1.27)) hide)
    )
  )
  (global_label "DSI1_LN2_N" (shape output) (at 269.875 54.61 0) (fields_autoplaced)
    (effects (font (size 1.27 1.27)) (justify left))
    (property "Intersheet References" "${INTERSHEET_REFS}" (id 0) (at 10.16 -6.35 0)
      (effects (font (size 1.27 1.27)) hide)
    )
  )
  (global_label "SD_CLK" (shape input) (at 120.015 68.58 0) (fields_autoplaced)
    (effects (font (size 1.27 1.27)) (justify left))
    (property "Intersheet References" "${INTERSHEET_REFS}" (id 0) (at 2.54 -15.875 0)
      (effects (font (size 1.27 1.27)) hide)
    )
  )
  (global_label "CSI1_LN3_N" (shape input) (at 45.085 58.42 180) (fields_autoplaced)
    (effects (font (size 1.27 1.27)) (justify right))
    (property "Intersheet References" "${INTERSHEET_REFS}" (id 0) (at -5.08 -10.795 0)
      (effects (font (size 1.27 1.27)) hide)
    )
  )
  (global_label "USB1_SS_RX1_P" (shape input) (at 194.945 146.05 180) (fields_autoplaced)
    (effects (font (size 1.27 1.27)) (justify right))
    (property "Intersheet References" "${INTERSHEET_REFS}" (id 0) (at 2.54 -21.59 0)
      (effects (font (size 1.27 1.27)) hide)
    )
  )
  (global_label "CCI0_I2C_SCL" (shape input) (at 45.085 170.18 180) (fields_autoplaced)
    (effects (font (size 1.27 1.27)) (justify right))
    (property "Intersheet References" "${INTERSHEET_REFS}" (id 0) (at -5.08 -36.195 0)
      (effects (font (size 1.27 1.27)) hide)
    )
  )
  (global_label "PCIE1_CLKREQ_N" (shape input) (at 120.015 124.46 0) (fields_autoplaced)
    (effects (font (size 1.27 1.27)) (justify left))
    (property "Intersheet References" "${INTERSHEET_REFS}" (id 0) (at 2.54 -41.275 0)
      (effects (font (size 1.27 1.27)) hide)
    )
  )
  (global_label "DSI1_LN3_P" (shape output) (at 269.875 57.15 0) (fields_autoplaced)
    (effects (font (size 1.27 1.27)) (justify left))
    (property "Intersheet References" "${INTERSHEET_REFS}" (id 0) (at 10.16 -11.43 0)
      (effects (font (size 1.27 1.27)) hide)
    )
  )
  (global_label "DSI1_CLK_N" (shape output) (at 269.875 49.53 0) (fields_autoplaced)
    (effects (font (size 1.27 1.27)) (justify left))
    (property "Intersheet References" "${INTERSHEET_REFS}" (id 0) (at 10.16 -3.81 0)
      (effects (font (size 1.27 1.27)) hide)
    )
  )
  (global_label "CCI1_I2C_SDA" (shape input) (at 45.085 175.26 180) (fields_autoplaced)
    (effects (font (size 1.27 1.27)) (justify right))
    (property "Intersheet References" "${INTERSHEET_REFS}" (id 0) (at -5.08 -36.195 0)
      (effects (font (size 1.27 1.27)) hide)
    )
  )
  (global_label "DSI1_LN1_P" (shape output) (at 269.875 62.23 0) (fields_autoplaced)
    (effects (font (size 1.27 1.27)) (justify left))
    (property "Intersheet References" "${INTERSHEET_REFS}" (id 0) (at 10.16 -13.97 0)
      (effects (font (size 1.27 1.27)) hide)
    )
  )
  (global_label "CSI0_LN0_N" (shape input) (at 45.085 48.26 180) (fields_autoplaced)
    (effects (font (size 1.27 1.27)) (justify right))
    (property "Intersheet References" "${INTERSHEET_REFS}" (id 0) (at -5.08 -5.715 0)
      (effects (font (size 1.27 1.27)) hide)
    )
  )
  (global_label "USB2_SS_TX_N" (shape output) (at 194.945 143.51 180) (fields_autoplaced)
    (effects (font (size 1.27 1.27)) (justify right))
    (property "Intersheet References" "${INTERSHEET_REFS}" (id 0) (at 2.54 -19.05 0)
      (effects (font (size 1.27 1.27)) hide)
    )
  )
  (global_label "SD_LDO21A" (shape output) (at 120.015 167.64 0) (fields_autoplaced)
    (effects (font (size 1.27 1.27)) (justify left))
    (property "Intersheet References" "${INTERSHEET_REFS}" (id 0) (at 2.54 -51.435 0)
      (effects (font (size 1.27 1.27)) hide)
    )
  )
  (global_label "I2S1_WS" (shape output) (at 269.875 107.95 0) (fields_autoplaced)
    (effects (font (size 1.27 1.27)) (justify left))
    (property "Intersheet References" "${INTERSHEET_REFS}" (id 0) (at 10.16 -19.05 0)
      (effects (font (size 1.27 1.27)) hide)
    )
  )
  (global_label "USB1_SS_TX1_P" (shape output) (at 269.875 143.51 0) (fields_autoplaced)
    (effects (font (size 1.27 1.27)) (justify left))
    (property "Intersheet References" "${INTERSHEET_REFS}" (id 0) (at 10.16 -26.67 0)
      (effects (font (size 1.27 1.27)) hide)
    )
  )
  (global_label "USB1_SS_RX0_N" (shape input) (at 194.945 153.67 180) (fields_autoplaced)
    (effects (font (size 1.27 1.27)) (justify right))
    (property "Intersheet References" "${INTERSHEET_REFS}" (id 0) (at 2.54 -21.59 0)
      (effects (font (size 1.27 1.27)) hide)
    )
  )
  (global_label "USB1_SS_TX0_N" (shape output) (at 269.875 156.21 0) (fields_autoplaced)
    (effects (font (size 1.27 1.27)) (justify left))
    (property "Intersheet References" "${INTERSHEET_REFS}" (id 0) (at 10.16 -26.67 0)
      (effects (font (size 1.27 1.27)) hide)
    )
  )
  (global_label "DSI0_LN2_N" (shape output) (at 194.945 49.53 180) (fields_autoplaced)
    (effects (font (size 1.27 1.27)) (justify right))
    (property "Intersheet References" "${INTERSHEET_REFS}" (id 0) (at 2.54 -1.27 0)
      (effects (font (size 1.27 1.27)) hide)
    )
  )
  (global_label "DBG_RXD" (shape input) (at 269.875 166.37 0) (fields_autoplaced)
    (effects (font (size 1.27 1.27)) (justify left))
    (property "Intersheet References" "${INTERSHEET_REFS}" (id 0) (at 10.16 -31.75 0)
      (effects (font (size 1.27 1.27)) hide)
    )
  )
  (global_label "CSI1_LN1_N" (shape input) (at 45.085 68.58 180) (fields_autoplaced)
    (effects (font (size 1.27 1.27)) (justify right))
    (property "Intersheet References" "${INTERSHEET_REFS}" (id 0) (at -5.08 -15.875 0)
      (effects (font (size 1.27 1.27)) hide)
    )
  )
  (global_label "CAM0_PWDN" (shape output) (at 45.085 134.62 180) (fields_autoplaced)
    (effects (font (size 1.27 1.27)) (justify right))
    (property "Intersheet References" "${INTERSHEET_REFS}" (id 0) (at -5.08 -36.195 0)
      (effects (font (size 1.27 1.27)) hide)
    )
  )
  (global_label "VREG_S4A_1V8" (shape output) (at 181.102 161.925 180) (fields_autoplaced)
    (effects (font (size 1.27 1.27)) (justify right))
    (property "Intersheet References" "${INTERSHEET_REFS}" (id 0) (at -11.303 -26.035 0)
      (effects (font (size 1.27 1.27)) hide)
    )
  )

  (symbol (lib_id "sa800u-baseboard-hw:Battery_Holder_MS621FE-FL11E") (at 316.23 172.72 0) (unit 1)
    (in_bom yes) (on_board yes) (fields_autoplaced)
    (property "Reference" "BAT1" (id 0) (at 320.675 175.895 0)
      (effects (font (size 1.524 1.524)) (justify left))
    )
    (property "Value" "Battery_Holder_MS621FE-FL11E" (id 1) (at 320.675 179.705 0)
      (effects (font (size 1.524 1.524)) (justify left) hide)
    )
    (property "Footprint" "sa800u-baseboard-hw-footprints:MS621FE-FL11E" (id 2) (at 316.23 172.72 0)
      (effects (font (size 1.524 1.524)) hide)
    )
    (property "Datasheet" "https://www.sii.co.jp/en/me/datasheets/ms-rechargeable/ms621fe/" (id 3) (at 316.23 172.72 0)
      (effects (font (size 1.524 1.524)) hide)
    )
    (property "Manufacturer" "Seiko" (id 4) (at 316.23 172.72 0)
      (effects (font (size 1.27 1.27)) hide)
    )
    (property "MPN" "MS621FE-FL11E" (id 5) (at 320.675 179.0699 0)
      (effects (font (size 1.27 1.27)) (justify left))
    )
    (property "Author" "Antmicro" (id 6) (at 334.01 194.31 0)
      (effects (font (size 1.27 1.27) (thickness 0.15)) (justify left bottom) hide)
    )
    (property "License" "Apache-2.0" (id 7) (at 334.01 196.85 0)
      (effects (font (size 1.27 1.27) (thickness 0.15)) (justify left bottom) hide)
    )
    (pin "+")
    (pin "-")
  )

  (symbol (lib_id "sa800u-baseboard-hw:GND") (at 55.372 192.786 0) (unit 1)
    (in_bom yes) (on_board yes) (fields_autoplaced)
    (property "Reference" "#PWR0103" (id 0) (at 55.372 199.136 0)
      (effects (font (size 1.27 1.27)) hide)
    )
    (property "Value" "GND" (id 1) (at 55.372 197.485 0))
    (property "Footprint" "" (id 2) (at 55.372 192.786 0)
      (effects (font (size 1.27 1.27)) hide)
    )
    (property "Datasheet" "" (id 3) (at 55.372 192.786 0)
      (effects (font (size 1.27 1.27)) hide)
    )
    (property "Author" "Antmicro" (id 4) (at 64.262 200.406 0)
      (effects (font (size 1.27 1.27) (thickness 0.15)) (justify left bottom) hide)
    )
    (property "License" "Apache-2.0" (id 5) (at 64.262 202.946 0)
      (effects (font (size 1.27 1.27) (thickness 0.15)) (justify left bottom) hide)
    )
    (pin "1")
  )

  (symbol (lib_id "sa800u-baseboard-hw:SW_SPST_KMR211NGLFS") (at 392.557 60.833 0) (mirror y) (unit 1)
    (in_bom yes) (on_board yes) (fields_autoplaced)
    (property "Reference" "S1" (id 0) (at 387.477 53.34 0))
    (property "Value" "SW_SPST_KMR211NGLFS" (id 1) (at 387.477 55.118 0)
      (effects (font (size 1.27 1.27)) hide)
    )
    (property "Footprint" "sa800u-baseboard-hw-footprints:SW_SPST_4.2x2.8" (id 2) (at 387.477 55.753 0)
      (effects (font (size 1.27 1.27)) (justify left) hide)
    )
    (property "Datasheet" "http://www.farnell.com/datasheets/2631211.pdf" (id 3) (at 387.477 53.213 0)
      (effects (font (size 1.524 1.524)) (justify left) hide)
    )
    (property "MPN" "KMR211NGLFS" (id 4) (at 387.477 55.88 0)
      (effects (font (size 1.524 1.524)))
    )
    (property "Manufacturer" "C&K" (id 5) (at 387.477 48.8442 0)
      (effects (font (size 1.524 1.524)) (justify left) hide)
    )
    (property "Author" "Antmicro" (id 6) (at 367.157 78.613 0)
      (effects (font (size 1.27 1.27) (thickness 0.15)) (justify left bottom) hide)
    )
    (property "License" "Apache-2.0" (id 7) (at 367.157 81.153 0)
      (effects (font (size 1.27 1.27) (thickness 0.15)) (justify left bottom) hide)
    )
    (pin "1")
    (pin "2")
    (pin "3")
    (pin "4")
  )

  (symbol (lib_id "sa800u-baseboard-hw:SW_SPST_KMR211NGLFS") (at 392.557 90.043 0) (mirror y) (unit 1)
    (in_bom yes) (on_board yes) (fields_autoplaced)
    (property "Reference" "S2" (id 0) (at 387.477 82.55 0))
    (property "Value" "SW_SPST_KMR211NGLFS" (id 1) (at 387.477 84.328 0)
      (effects (font (size 1.27 1.27)) hide)
    )
    (property "Footprint" "sa800u-baseboard-hw-footprints:SW_SPST_4.2x2.8" (id 2) (at 387.477 84.963 0)
      (effects (font (size 1.27 1.27)) (justify left) hide)
    )
    (property "Datasheet" "http://www.farnell.com/datasheets/2631211.pdf" (id 3) (at 387.477 82.423 0)
      (effects (font (size 1.524 1.524)) (justify left) hide)
    )
    (property "MPN" "KMR211NGLFS" (id 4) (at 387.477 85.09 0)
      (effects (font (size 1.524 1.524)))
    )
    (property "Manufacturer" "C&K" (id 5) (at 387.477 78.0542 0)
      (effects (font (size 1.524 1.524)) (justify left) hide)
    )
    (property "Author" "Antmicro" (id 6) (at 367.157 107.823 0)
      (effects (font (size 1.27 1.27) (thickness 0.15)) (justify left bottom) hide)
    )
    (property "License" "Apache-2.0" (id 7) (at 367.157 110.363 0)
      (effects (font (size 1.27 1.27) (thickness 0.15)) (justify left bottom) hide)
    )
    (pin "1")
    (pin "2")
    (pin "3")
    (pin "4")
  )

  (symbol (lib_id "sa800u-baseboard-hw:SW_SPST_KMR211NGLFS") (at 392.557 117.983 0) (mirror y) (unit 1)
    (in_bom yes) (on_board yes) (fields_autoplaced)
    (property "Reference" "S3" (id 0) (at 387.477 110.49 0))
    (property "Value" "SW_SPST_KMR211NGLFS" (id 1) (at 387.477 112.268 0)
      (effects (font (size 1.27 1.27)) hide)
    )
    (property "Footprint" "sa800u-baseboard-hw-footprints:SW_SPST_4.2x2.8" (id 2) (at 387.477 112.903 0)
      (effects (font (size 1.27 1.27)) (justify left) hide)
    )
    (property "Datasheet" "http://www.farnell.com/datasheets/2631211.pdf" (id 3) (at 387.477 110.363 0)
      (effects (font (size 1.524 1.524)) (justify left) hide)
    )
    (property "MPN" "KMR211NGLFS" (id 4) (at 387.477 113.03 0)
      (effects (font (size 1.524 1.524)))
    )
    (property "Manufacturer" "C&K" (id 5) (at 387.477 105.9942 0)
      (effects (font (size 1.524 1.524)) (justify left) hide)
    )
    (property "Author" "Antmicro" (id 6) (at 367.157 135.763 0)
      (effects (font (size 1.27 1.27) (thickness 0.15)) (justify left bottom) hide)
    )
    (property "License" "Apache-2.0" (id 7) (at 367.157 138.303 0)
      (effects (font (size 1.27 1.27) (thickness 0.15)) (justify left bottom) hide)
    )
    (pin "1")
    (pin "2")
    (pin "3")
    (pin "4")
  )

  (symbol (lib_id "sa800u-baseboard-hw:SW_SPST_KMR211NGLFS") (at 393.827 145.923 0) (mirror y) (unit 1)
    (in_bom yes) (on_board yes) (fields_autoplaced)
    (property "Reference" "S4" (id 0) (at 388.747 138.43 0))
    (property "Value" "SW_SPST_KMR211NGLFS" (id 1) (at 388.747 140.208 0)
      (effects (font (size 1.27 1.27)) hide)
    )
    (property "Footprint" "sa800u-baseboard-hw-footprints:SW_SPST_4.2x2.8" (id 2) (at 388.747 140.843 0)
      (effects (font (size 1.27 1.27)) (justify left) hide)
    )
    (property "Datasheet" "http://www.farnell.com/datasheets/2631211.pdf" (id 3) (at 388.747 138.303 0)
      (effects (font (size 1.524 1.524)) (justify left) hide)
    )
    (property "MPN" "KMR211NGLFS" (id 4) (at 388.747 140.97 0)
      (effects (font (size 1.524 1.524)))
    )
    (property "Manufacturer" "C&K" (id 5) (at 388.747 133.9342 0)
      (effects (font (size 1.524 1.524)) (justify left) hide)
    )
    (property "Author" "Antmicro" (id 6) (at 368.427 163.703 0)
      (effects (font (size 1.27 1.27) (thickness 0.15)) (justify left bottom) hide)
    )
    (property "License" "Apache-2.0" (id 7) (at 368.427 166.243 0)
      (effects (font (size 1.27 1.27) (thickness 0.15)) (justify left bottom) hide)
    )
    (pin "1")
    (pin "2")
    (pin "3")
    (pin "4")
  )

  (symbol (lib_id "sa800u-baseboard-hw:R_1k_0402") (at 360.807 145.923 0) (mirror y) (unit 1)
    (in_bom yes) (on_board yes) (fields_autoplaced)
    (property "Reference" "R76" (id 0) (at 358.267 138.938 0)
      (effects (font (size 1.524 1.524)))
    )
    (property "Value" "R_1k_0402" (id 1) (at 360.807 149.733 0)
      (effects (font (size 1.524 1.524)) hide)
    )
    (property "Footprint" "sa800u-baseboard-hw-footprints:R_0402_1005Metric" (id 2) (at 355.727 140.843 0)
      (effects (font (size 1.524 1.524)) (justify left) hide)
    )
    (property "Datasheet" "https://www.bourns.com/docs/product-datasheets/cr.pdf" (id 3) (at 360.807 145.923 0)
      (effects (font (size 1.27 1.27)) hide)
    )
    (property "Manufacturer" "Bourns" (id 4) (at 355.727 135.763 0)
      (effects (font (size 1.524 1.524)) (justify left) hide)
    )
    (property "MPN" "CR0402-FX-1001GLF" (id 5) (at 355.727 138.303 0)
      (effects (font (size 1.524 1.524)) (justify left) hide)
    )
    (property "Val" "1k" (id 6) (at 358.267 142.748 0))
    (property "License" "Apache-2.0" (id 7) (at 340.487 171.323 0)
      (effects (font (size 1.27 1.27) (thickness 0.15)) (justify left bottom) hide)
    )
    (property "Author" "Antmicro" (id 8) (at 340.487 173.863 0)
      (effects (font (size 1.27 1.27) (thickness 0.15)) (justify left bottom) hide)
    )
    (property "Tolerance" "1%" (id 9) (at 340.487 156.083 0)
      (effects (font (size 1.27 1.27)) (justify left bottom) hide)
    )
    (pin "1")
    (pin "2")
  )

  (symbol (lib_id "sa800u-baseboard-hw:C_100u_0805") (at 122.936 251.333 270) (unit 1)
    (in_bom yes) (on_board yes) (fields_autoplaced)
    (property "Reference" "C101" (id 0) (at 125.857 252.6093 90)
      (effects (font (size 1.524 1.524)) (justify left))
    )
    (property "Value" "C_100u_0805" (id 1) (at 119.126 251.333 0)
      (effects (font (size 1.524 1.524)) hide)
    )
    (property "Footprint" "sa800u-baseboard-hw-footprints:C_0805_2012Metric" (id 2) (at 128.016 256.413 0)
      (effects (font (size 1.524 1.524)) (justify left) hide)
    )
    (property "Datasheet" " " (id 3) (at 122.936 251.333 0)
      (effects (font (size 1.27 1.27)) hide)
    )
    (property "Manufacturer" "Murata" (id 4) (at 133.096 256.413 0)
      (effects (font (size 1.524 1.524)) (justify left) hide)
    )
    (property "MPN" "GRM21BR60J107ME15L" (id 5) (at 130.556 256.413 0)
      (effects (font (size 1.524 1.524)) (justify left) hide)
    )
    (property "Val" "100u" (id 6) (at 125.857 255.7842 90)
      (effects (font (size 1.27 1.27)) (justify left))
    )
    (property "License" "Apache-2.0" (id 7) (at 100.076 271.653 0)
      (effects (font (size 1.27 1.27) (thickness 0.15)) (justify left bottom) hide)
    )
    (property "Author" "Antmicro" (id 8) (at 97.536 271.653 0)
      (effects (font (size 1.27 1.27) (thickness 0.15)) (justify left bottom) hide)
    )
    (property "Voltage" "" (id 9) (at 94.996 271.653 0)
      (effects (font (size 1.27 1.27)) (justify left bottom) hide)
    )
    (property "Dielectric" "" (id 10) (at 92.456 271.653 0)
      (effects (font (size 1.27 1.27)) (justify left bottom) hide)
    )
    (pin "1")
    (pin "2")
  )

  (symbol (lib_id "sa800u-baseboard-hw:C_100n_0402") (at 134.366 251.206 270) (unit 1)
    (in_bom yes) (on_board yes) (fields_autoplaced)
    (property "Reference" "C102" (id 0) (at 137.16 252.4823 90)
      (effects (font (size 1.524 1.524)) (justify left))
    )
    (property "Value" "C_100n_0402" (id 1) (at 130.556 251.206 0)
      (effects (font (size 1.524 1.524)) hide)
    )
    (property "Footprint" "sa800u-baseboard-hw-footprints:C_0402_1005Metric" (id 2) (at 139.446 256.286 0)
      (effects (font (size 1.524 1.524)) (justify left) hide)
    )
    (property "Datasheet" "https://search.murata.co.jp/Ceramy/image/img/A01X/G101/ENG/GRM155R61H104KE14-01.pdf" (id 3) (at 134.366 251.206 0)
      (effects (font (size 1.27 1.27)) hide)
    )
    (property "Manufacturer" "Murata" (id 4) (at 144.526 256.286 0)
      (effects (font (size 1.524 1.524)) (justify left) hide)
    )
    (property "MPN" "GRM155R61H104KE14D" (id 5) (at 141.986 256.286 0)
      (effects (font (size 1.524 1.524)) (justify left) hide)
    )
    (property "Val" "100n" (id 6) (at 137.16 255.6572 90)
      (effects (font (size 1.27 1.27)) (justify left))
    )
    (property "License" "Apache-2.0" (id 7) (at 111.506 271.526 0)
      (effects (font (size 1.27 1.27) (thickness 0.15)) (justify left bottom) hide)
    )
    (property "Author" "Antmicro" (id 8) (at 108.966 271.526 0)
      (effects (font (size 1.27 1.27) (thickness 0.15)) (justify left bottom) hide)
    )
    (property "Voltage" "50V" (id 9) (at 106.426 271.526 0)
      (effects (font (size 1.27 1.27)) (justify left bottom) hide)
    )
    (property "Dielectric" "X5R" (id 10) (at 103.886 271.526 0)
      (effects (font (size 1.27 1.27)) (justify left bottom) hide)
    )
    (pin "1")
    (pin "2")
  )

  (symbol (lib_id "sa800u-baseboard-hw:C_33p_0402") (at 145.796 251.206 270) (unit 1)
    (in_bom yes) (on_board yes) (fields_autoplaced)
    (property "Reference" "C103" (id 0) (at 148.717 252.4823 90)
      (effects (font (size 1.524 1.524)) (justify left))
    )
    (property "Value" "C_33p_0402" (id 1) (at 141.986 251.206 0)
      (effects (font (size 1.524 1.524)) hide)
    )
    (property "Footprint" "sa800u-baseboard-hw-footprints:C_0402_1005Metric" (id 2) (at 150.876 256.286 0)
      (effects (font (size 1.524 1.524)) (justify left) hide)
    )
    (property "Datasheet" " " (id 3) (at 145.796 251.206 0)
      (effects (font (size 1.27 1.27)) hide)
    )
    (property "Manufacturer" "Multicomp" (id 4) (at 155.956 256.286 0)
      (effects (font (size 1.524 1.524)) (justify left) hide)
    )
    (property "MPN" "MC0402N330J500CT" (id 5) (at 153.416 256.286 0)
      (effects (font (size 1.524 1.524)) (justify left) hide)
    )
    (property "Val" "33p" (id 6) (at 148.717 255.6572 90)
      (effects (font (size 1.27 1.27)) (justify left))
    )
    (property "License" "Apache-2.0" (id 7) (at 122.936 271.526 0)
      (effects (font (size 1.27 1.27) (thickness 0.15)) (justify left bottom) hide)
    )
    (property "Author" "Antmicro" (id 8) (at 120.396 271.526 0)
      (effects (font (size 1.27 1.27) (thickness 0.15)) (justify left bottom) hide)
    )
    (property "Voltage" "" (id 9) (at 117.856 271.526 0)
      (effects (font (size 1.27 1.27)) (justify left bottom) hide)
    )
    (property "Dielectric" "" (id 10) (at 115.316 271.526 0)
      (effects (font (size 1.27 1.27)) (justify left bottom) hide)
    )
    (pin "1")
    (pin "2")
  )

  (symbol (lib_id "sa800u-baseboard-hw:C_10p_0402") (at 155.956 251.206 270) (unit 1)
    (in_bom yes) (on_board yes) (fields_autoplaced)
    (property "Reference" "C104" (id 0) (at 158.369 252.4823 90)
      (effects (font (size 1.524 1.524)) (justify left))
    )
    (property "Value" "C_10p_0402" (id 1) (at 152.146 251.206 0)
      (effects (font (size 1.524 1.524)) hide)
    )
    (property "Footprint" "sa800u-baseboard-hw-footprints:C_0402_1005Metric" (id 2) (at 161.036 256.286 0)
      (effects (font (size 1.524 1.524)) (justify left) hide)
    )
    (property "Datasheet" "https://search.murata.co.jp/Ceramy/image/img/A01X/G101/ENG/GCM1555C1H100GA16-01.pdf" (id 3) (at 155.956 251.206 0)
      (effects (font (size 1.27 1.27)) hide)
    )
    (property "Manufacturer" "Murata" (id 4) (at 166.116 256.286 0)
      (effects (font (size 1.524 1.524)) (justify left) hide)
    )
    (property "MPN" "GCM1555C1H100GA16D" (id 5) (at 163.576 256.286 0)
      (effects (font (size 1.524 1.524)) (justify left) hide)
    )
    (property "Val" "10p" (id 6) (at 158.369 255.6572 90)
      (effects (font (size 1.27 1.27)) (justify left))
    )
    (property "License" "Apache-2.0" (id 7) (at 133.096 271.526 0)
      (effects (font (size 1.27 1.27) (thickness 0.15)) (justify left bottom) hide)
    )
    (property "Author" "Antmicro" (id 8) (at 130.556 271.526 0)
      (effects (font (size 1.27 1.27) (thickness 0.15)) (justify left bottom) hide)
    )
    (property "Voltage" "50V" (id 9) (at 128.016 271.526 0)
      (effects (font (size 1.27 1.27)) (justify left bottom) hide)
    )
    (property "Dielectric" "C0G" (id 10) (at 125.476 271.526 0)
      (effects (font (size 1.27 1.27)) (justify left bottom) hide)
    )
    (pin "1")
    (pin "2")
  )

  (symbol (lib_id "sa800u-baseboard-hw:GND") (at 206.502 205.74 0) (unit 1)
    (in_bom yes) (on_board yes) (fields_autoplaced)
    (property "Reference" "#PWR0141" (id 0) (at 206.502 212.09 0)
      (effects (font (size 1.27 1.27)) hide)
    )
    (property "Value" "GND" (id 1) (at 206.502 210.82 0))
    (property "Footprint" "" (id 2) (at 206.502 205.74 0)
      (effects (font (size 1.27 1.27)) hide)
    )
    (property "Datasheet" "" (id 3) (at 206.502 205.74 0)
      (effects (font (size 1.27 1.27)) hide)
    )
    (property "Author" "Antmicro" (id 4) (at 215.392 213.36 0)
      (effects (font (size 1.27 1.27) (thickness 0.15)) (justify left bottom) hide)
    )
    (property "License" "Apache-2.0" (id 5) (at 215.392 215.9 0)
      (effects (font (size 1.27 1.27) (thickness 0.15)) (justify left bottom) hide)
    )
    (pin "1")
  )

  (symbol (lib_id "sa800u-baseboard-hw:C_100u_0805") (at 112.776 251.206 270) (unit 1)
    (in_bom yes) (on_board yes) (fields_autoplaced)
    (property "Reference" "C100" (id 0) (at 115.443 252.4823 90)
      (effects (font (size 1.524 1.524)) (justify left))
    )
    (property "Value" "C_100u_0805" (id 1) (at 108.966 251.206 0)
      (effects (font (size 1.524 1.524)) hide)
    )
    (property "Footprint" "sa800u-baseboard-hw-footprints:C_0805_2012Metric" (id 2) (at 117.856 256.286 0)
      (effects (font (size 1.524 1.524)) (justify left) hide)
    )
    (property "Datasheet" " " (id 3) (at 112.776 251.206 0)
      (effects (font (size 1.27 1.27)) hide)
    )
    (property "Manufacturer" "Murata" (id 4) (at 122.936 256.286 0)
      (effects (font (size 1.524 1.524)) (justify left) hide)
    )
    (property "MPN" "GRM21BR60J107ME15L" (id 5) (at 120.396 256.286 0)
      (effects (font (size 1.524 1.524)) (justify left) hide)
    )
    (property "Val" "100u" (id 6) (at 115.443 255.6572 90)
      (effects (font (size 1.27 1.27)) (justify left))
    )
    (property "License" "Apache-2.0" (id 7) (at 89.916 271.526 0)
      (effects (font (size 1.27 1.27) (thickness 0.15)) (justify left bottom) hide)
    )
    (property "Author" "Antmicro" (id 8) (at 87.376 271.526 0)
      (effects (font (size 1.27 1.27) (thickness 0.15)) (justify left bottom) hide)
    )
    (property "Voltage" "" (id 9) (at 84.836 271.526 0)
      (effects (font (size 1.27 1.27)) (justify left bottom) hide)
    )
    (property "Dielectric" "" (id 10) (at 82.296 271.526 0)
      (effects (font (size 1.27 1.27)) (justify left bottom) hide)
    )
    (pin "1")
    (pin "2")
  )

  (symbol (lib_id "sa800u-baseboard-hw:C_100u_0805") (at 102.616 251.206 270) (unit 1)
    (in_bom yes) (on_board yes) (fields_autoplaced)
    (property "Reference" "C99" (id 0) (at 105.41 252.4823 90)
      (effects (font (size 1.524 1.524)) (justify left))
    )
    (property "Value" "C_100u_0805" (id 1) (at 98.806 251.206 0)
      (effects (font (size 1.524 1.524)) hide)
    )
    (property "Footprint" "sa800u-baseboard-hw-footprints:C_0805_2012Metric" (id 2) (at 107.696 256.286 0)
      (effects (font (size 1.524 1.524)) (justify left) hide)
    )
    (property "Datasheet" " " (id 3) (at 102.616 251.206 0)
      (effects (font (size 1.27 1.27)) hide)
    )
    (property "Manufacturer" "Murata" (id 4) (at 112.776 256.286 0)
      (effects (font (size 1.524 1.524)) (justify left) hide)
    )
    (property "MPN" "GRM21BR60J107ME15L" (id 5) (at 110.236 256.286 0)
      (effects (font (size 1.524 1.524)) (justify left) hide)
    )
    (property "Val" "100u" (id 6) (at 105.41 255.6572 90)
      (effects (font (size 1.27 1.27)) (justify left))
    )
    (property "License" "Apache-2.0" (id 7) (at 79.756 271.526 0)
      (effects (font (size 1.27 1.27) (thickness 0.15)) (justify left bottom) hide)
    )
    (property "Author" "Antmicro" (id 8) (at 77.216 271.526 0)
      (effects (font (size 1.27 1.27) (thickness 0.15)) (justify left bottom) hide)
    )
    (property "Voltage" "" (id 9) (at 74.676 271.526 0)
      (effects (font (size 1.27 1.27)) (justify left bottom) hide)
    )
    (property "Dielectric" "" (id 10) (at 72.136 271.526 0)
      (effects (font (size 1.27 1.27)) (justify left bottom) hide)
    )
    (pin "1")
    (pin "2")
  )

  (symbol (lib_id "sa800u-baseboard-hw:GND") (at 122.936 261.366 0) (unit 1)
    (in_bom yes) (on_board yes) (fields_autoplaced)
    (property "Reference" "#PWR0105" (id 0) (at 122.936 267.716 0)
      (effects (font (size 1.27 1.27)) hide)
    )
    (property "Value" "GND" (id 1) (at 120.396 262.6359 0)
      (effects (font (size 1.27 1.27)) (justify right))
    )
    (property "Footprint" "" (id 2) (at 122.936 261.366 0)
      (effects (font (size 1.27 1.27)) hide)
    )
    (property "Datasheet" "" (id 3) (at 122.936 261.366 0)
      (effects (font (size 1.27 1.27)) hide)
    )
    (property "Author" "Antmicro" (id 4) (at 131.826 268.986 0)
      (effects (font (size 1.27 1.27) (thickness 0.15)) (justify left bottom) hide)
    )
    (property "License" "Apache-2.0" (id 5) (at 131.826 271.526 0)
      (effects (font (size 1.27 1.27) (thickness 0.15)) (justify left bottom) hide)
    )
    (pin "1")
  )

  (symbol (lib_id "sa800u-baseboard-hw:R_47k_0402") (at 285.75 180.34 270) (unit 1)
    (in_bom yes) (on_board yes) (fields_autoplaced)
    (property "Reference" "R70" (id 0) (at 288.29 181.61 90)
      (effects (font (size 1.524 1.524)) (justify left))
    )
    (property "Value" "R_47k_0402" (id 1) (at 281.94 180.34 0)
      (effects (font (size 1.524 1.524)) hide)
    )
    (property "Footprint" "sa800u-baseboard-hw-footprints:R_0402_1005Metric" (id 2) (at 290.83 185.42 0)
      (effects (font (size 1.524 1.524)) (justify left) hide)
    )
    (property "Datasheet" "https://www.bourns.com/docs/product-datasheets/cr.pdf" (id 3) (at 285.75 180.34 0)
      (effects (font (size 1.27 1.27)) hide)
    )
    (property "Manufacturer" "Bourns" (id 4) (at 295.91 185.42 0)
      (effects (font (size 1.524 1.524)) (justify left) hide)
    )
    (property "MPN" "CR0402-FX-4702GLF" (id 5) (at 293.37 185.42 0)
      (effects (font (size 1.524 1.524)) (justify left) hide)
    )
    (property "Val" "47k" (id 6) (at 288.29 184.7849 90)
      (effects (font (size 1.27 1.27)) (justify left))
    )
    (property "License" "Apache-2.0" (id 7) (at 260.35 200.66 0)
      (effects (font (size 1.27 1.27) (thickness 0.15)) (justify left bottom) hide)
    )
    (property "Author" "Antmicro" (id 8) (at 257.81 200.66 0)
      (effects (font (size 1.27 1.27) (thickness 0.15)) (justify left bottom) hide)
    )
    (property "Tolerance" "1%" (id 9) (at 275.59 200.66 0)
      (effects (font (size 1.27 1.27)) (justify left bottom) hide)
    )
    (pin "1")
    (pin "2")
  )

  (symbol (lib_id "sa800u-baseboard-hw:GND") (at 285.75 185.42 0) (unit 1)
    (in_bom yes) (on_board yes) (fields_autoplaced)
    (property "Reference" "#PWR0159" (id 0) (at 285.75 191.77 0)
      (effects (font (size 1.27 1.27)) hide)
    )
    (property "Value" "GND" (id 1) (at 283.21 186.6899 0)
      (effects (font (size 1.27 1.27)) (justify right))
    )
    (property "Footprint" "" (id 2) (at 285.75 185.42 0)
      (effects (font (size 1.27 1.27)) hide)
    )
    (property "Datasheet" "" (id 3) (at 285.75 185.42 0)
      (effects (font (size 1.27 1.27)) hide)
    )
    (property "Author" "Antmicro" (id 4) (at 294.64 193.04 0)
      (effects (font (size 1.27 1.27) (thickness 0.15)) (justify left bottom) hide)
    )
    (property "License" "Apache-2.0" (id 5) (at 294.64 195.58 0)
      (effects (font (size 1.27 1.27) (thickness 0.15)) (justify left bottom) hide)
    )
    (pin "1")
  )

  (symbol (lib_id "sa800u-baseboard-hw:R_1k_0402") (at 290.83 271.78 270) (unit 1)
    (in_bom yes) (on_board yes) (fields_autoplaced)
    (property "Reference" "R69" (id 0) (at 293.37 273.05 90)
      (effects (font (size 1.524 1.524)) (justify left))
    )
    (property "Value" "R_1k_0402" (id 1) (at 287.02 271.78 0)
      (effects (font (size 1.524 1.524)) hide)
    )
    (property "Footprint" "sa800u-baseboard-hw-footprints:R_0402_1005Metric" (id 2) (at 295.91 276.86 0)
      (effects (font (size 1.524 1.524)) (justify left) hide)
    )
    (property "Datasheet" "https://www.bourns.com/docs/product-datasheets/cr.pdf" (id 3) (at 290.83 271.78 0)
      (effects (font (size 1.27 1.27)) hide)
    )
    (property "Manufacturer" "Bourns" (id 4) (at 300.99 276.86 0)
      (effects (font (size 1.524 1.524)) (justify left) hide)
    )
    (property "MPN" "CR0402-FX-1001GLF" (id 5) (at 298.45 276.86 0)
      (effects (font (size 1.524 1.524)) (justify left) hide)
    )
    (property "Val" "1k" (id 6) (at 293.37 276.2249 90)
      (effects (font (size 1.27 1.27)) (justify left))
    )
    (property "License" "Apache-2.0" (id 7) (at 265.43 292.1 0)
      (effects (font (size 1.27 1.27) (thickness 0.15)) (justify left bottom) hide)
    )
    (property "Author" "Antmicro" (id 8) (at 262.89 292.1 0)
      (effects (font (size 1.27 1.27) (thickness 0.15)) (justify left bottom) hide)
    )
    (property "Tolerance" "1%" (id 9) (at 280.67 292.1 0)
      (effects (font (size 1.27 1.27)) (justify left bottom) hide)
    )
    (pin "1")
    (pin "2")
  )

  (symbol (lib_id "sa800u-baseboard-hw:STS321045B502") (at 96.901 251.206 270) (unit 1)
    (in_bom yes) (on_board yes) (fields_autoplaced)
    (property "Reference" "D13" (id 0) (at 93.98 255.0159 90)
      (effects (font (size 1.27 1.27)) (justify right))
    )
    (property "Value" "STS321045B502" (id 1) (at 93.98 257.5559 90)
      (effects (font (size 1.27 1.27)) (justify right))
    )
    (property "Footprint" "sa800u-baseboard-hw-footprints:SOD-323" (id 2) (at 96.901 251.206 0)
      (effects (font (size 1.27 1.27)) hide)
    )
    (property "Datasheet" "https://www.eaton.com/content/dam/eaton/products/electronic-components/resources/data-sheet/eaton-sts321045b502-tvs-diode-esd-suppressor-data-sheet.pdf" (id 3) (at 96.901 251.206 0)
      (effects (font (size 1.27 1.27)) hide)
    )
    (property "MPN" "STS321045B502" (id 4) (at 96.901 251.206 0)
      (effects (font (size 1.27 1.27)) hide)
    )
    (property "Manufacturer" "Cooper Bussmann" (id 5) (at 96.901 251.206 0)
      (effects (font (size 1.27 1.27)) hide)
    )
    (property "Author" "Antmicro" (id 6) (at 76.581 276.606 0)
      (effects (font (size 1.27 1.27) (thickness 0.15)) (justify left bottom) hide)
    )
    (property "License" "Apache-2.0" (id 7) (at 74.041 276.606 0)
      (effects (font (size 1.27 1.27) (thickness 0.15)) (justify left bottom) hide)
    )
    (pin "A")
    (pin "K")
  )

  (symbol (lib_id "sa800u-baseboard-hw:GND") (at 96.901 261.366 0) (unit 1)
    (in_bom yes) (on_board yes) (fields_autoplaced)
    (property "Reference" "#PWR0104" (id 0) (at 96.901 267.716 0)
      (effects (font (size 1.27 1.27)) hide)
    )
    (property "Value" "GND" (id 1) (at 94.996 262.6359 0)
      (effects (font (size 1.27 1.27)) (justify right))
    )
    (property "Footprint" "" (id 2) (at 96.901 261.366 0)
      (effects (font (size 1.27 1.27)) hide)
    )
    (property "Datasheet" "" (id 3) (at 96.901 261.366 0)
      (effects (font (size 1.27 1.27)) hide)
    )
    (property "Author" "Antmicro" (id 4) (at 105.791 268.986 0)
      (effects (font (size 1.27 1.27) (thickness 0.15)) (justify left bottom) hide)
    )
    (property "License" "Apache-2.0" (id 5) (at 105.791 271.526 0)
      (effects (font (size 1.27 1.27) (thickness 0.15)) (justify left bottom) hide)
    )
    (pin "1")
  )

  (symbol (lib_id "sa800u-baseboard-hw:GND") (at 290.83 276.86 0) (unit 1)
    (in_bom yes) (on_board yes) (fields_autoplaced)
    (property "Reference" "#PWR086" (id 0) (at 290.83 283.21 0)
      (effects (font (size 1.27 1.27)) hide)
    )
    (property "Value" "GND" (id 1) (at 290.83 281.94 0))
    (property "Footprint" "" (id 2) (at 290.83 276.86 0)
      (effects (font (size 1.27 1.27)) hide)
    )
    (property "Datasheet" "" (id 3) (at 290.83 276.86 0)
      (effects (font (size 1.27 1.27)) hide)
    )
    (property "Author" "Antmicro" (id 4) (at 299.72 284.48 0)
      (effects (font (size 1.27 1.27) (thickness 0.15)) (justify left bottom) hide)
    )
    (property "License" "Apache-2.0" (id 5) (at 299.72 287.02 0)
      (effects (font (size 1.27 1.27) (thickness 0.15)) (justify left bottom) hide)
    )
    (pin "1")
  )

  (symbol (lib_id "sa800u-baseboard-hw:R_1k_0402") (at 358.267 117.983 0) (mirror y) (unit 1)
    (in_bom yes) (on_board yes) (fields_autoplaced)
    (property "Reference" "R75" (id 0) (at 355.727 110.998 0)
      (effects (font (size 1.524 1.524)))
    )
    (property "Value" "R_1k_0402" (id 1) (at 358.267 121.793 0)
      (effects (font (size 1.524 1.524)) hide)
    )
    (property "Footprint" "sa800u-baseboard-hw-footprints:R_0402_1005Metric" (id 2) (at 353.187 112.903 0)
      (effects (font (size 1.524 1.524)) (justify left) hide)
    )
    (property "Datasheet" "https://www.bourns.com/docs/product-datasheets/cr.pdf" (id 3) (at 358.267 117.983 0)
      (effects (font (size 1.27 1.27)) hide)
    )
    (property "Manufacturer" "Bourns" (id 4) (at 353.187 107.823 0)
      (effects (font (size 1.524 1.524)) (justify left) hide)
    )
    (property "MPN" "CR0402-FX-1001GLF" (id 5) (at 353.187 110.363 0)
      (effects (font (size 1.524 1.524)) (justify left) hide)
    )
    (property "Val" "1k" (id 6) (at 355.727 114.808 0))
    (property "License" "Apache-2.0" (id 7) (at 337.947 143.383 0)
      (effects (font (size 1.27 1.27) (thickness 0.15)) (justify left bottom) hide)
    )
    (property "Author" "Antmicro" (id 8) (at 337.947 145.923 0)
      (effects (font (size 1.27 1.27) (thickness 0.15)) (justify left bottom) hide)
    )
    (property "Tolerance" "1%" (id 9) (at 337.947 128.143 0)
      (effects (font (size 1.27 1.27)) (justify left bottom) hide)
    )
    (pin "1")
    (pin "2")
  )

  (symbol (lib_id "sa800u-baseboard-hw:R_1k_0402") (at 358.267 90.043 0) (mirror y) (unit 1)
    (in_bom yes) (on_board yes) (fields_autoplaced)
    (property "Reference" "R74" (id 0) (at 355.727 83.058 0)
      (effects (font (size 1.524 1.524)))
    )
    (property "Value" "R_1k_0402" (id 1) (at 358.267 93.853 0)
      (effects (font (size 1.524 1.524)) hide)
    )
    (property "Footprint" "sa800u-baseboard-hw-footprints:R_0402_1005Metric" (id 2) (at 353.187 84.963 0)
      (effects (font (size 1.524 1.524)) (justify left) hide)
    )
    (property "Datasheet" "https://www.bourns.com/docs/product-datasheets/cr.pdf" (id 3) (at 358.267 90.043 0)
      (effects (font (size 1.27 1.27)) hide)
    )
    (property "Manufacturer" "Bourns" (id 4) (at 353.187 79.883 0)
      (effects (font (size 1.524 1.524)) (justify left) hide)
    )
    (property "MPN" "CR0402-FX-1001GLF" (id 5) (at 353.187 82.423 0)
      (effects (font (size 1.524 1.524)) (justify left) hide)
    )
    (property "Val" "1k" (id 6) (at 355.727 86.868 0))
    (property "License" "Apache-2.0" (id 7) (at 337.947 115.443 0)
      (effects (font (size 1.27 1.27) (thickness 0.15)) (justify left bottom) hide)
    )
    (property "Author" "Antmicro" (id 8) (at 337.947 117.983 0)
      (effects (font (size 1.27 1.27) (thickness 0.15)) (justify left bottom) hide)
    )
    (property "Tolerance" "1%" (id 9) (at 337.947 100.203 0)
      (effects (font (size 1.27 1.27)) (justify left bottom) hide)
    )
    (pin "1")
    (pin "2")
  )

  (symbol (lib_id "sa800u-baseboard-hw:GND") (at 393.827 64.643 0) (mirror y) (unit 1)
    (in_bom yes) (on_board yes) (fields_autoplaced)
    (property "Reference" "#PWR0168" (id 0) (at 393.827 70.993 0)
      (effects (font (size 1.27 1.27)) hide)
    )
    (property "Value" "GND" (id 1) (at 393.827 69.088 0))
    (property "Footprint" "" (id 2) (at 393.827 64.643 0)
      (effects (font (size 1.27 1.27)) hide)
    )
    (property "Datasheet" "" (id 3) (at 393.827 64.643 0)
      (effects (font (size 1.27 1.27)) hide)
    )
    (property "Author" "Antmicro" (id 4) (at 384.937 72.263 0)
      (effects (font (size 1.27 1.27) (thickness 0.15)) (justify left bottom) hide)
    )
    (property "License" "Apache-2.0" (id 5) (at 384.937 74.803 0)
      (effects (font (size 1.27 1.27) (thickness 0.15)) (justify left bottom) hide)
    )
    (pin "1")
  )

  (symbol (lib_id "sa800u-baseboard-hw:R_1k_0402") (at 358.267 60.833 0) (mirror y) (unit 1)
    (in_bom yes) (on_board yes) (fields_autoplaced)
    (property "Reference" "R73" (id 0) (at 355.727 53.848 0)
      (effects (font (size 1.524 1.524)))
    )
    (property "Value" "R_1k_0402" (id 1) (at 358.267 64.643 0)
      (effects (font (size 1.524 1.524)) hide)
    )
    (property "Footprint" "sa800u-baseboard-hw-footprints:R_0402_1005Metric" (id 2) (at 353.187 55.753 0)
      (effects (font (size 1.524 1.524)) (justify left) hide)
    )
    (property "Datasheet" "https://www.bourns.com/docs/product-datasheets/cr.pdf" (id 3) (at 358.267 60.833 0)
      (effects (font (size 1.27 1.27)) hide)
    )
    (property "Manufacturer" "Bourns" (id 4) (at 353.187 50.673 0)
      (effects (font (size 1.524 1.524)) (justify left) hide)
    )
    (property "MPN" "CR0402-FX-1001GLF" (id 5) (at 353.187 53.213 0)
      (effects (font (size 1.524 1.524)) (justify left) hide)
    )
    (property "Val" "1k" (id 6) (at 355.727 57.658 0))
    (property "License" "Apache-2.0" (id 7) (at 337.947 86.233 0)
      (effects (font (size 1.27 1.27) (thickness 0.15)) (justify left bottom) hide)
    )
    (property "Author" "Antmicro" (id 8) (at 337.947 88.773 0)
      (effects (font (size 1.27 1.27) (thickness 0.15)) (justify left bottom) hide)
    )
    (property "Tolerance" "1%" (id 9) (at 337.947 70.993 0)
      (effects (font (size 1.27 1.27)) (justify left bottom) hide)
    )
    (pin "1")
    (pin "2")
  )

  (symbol (lib_id "sa800u-baseboard-hw:R_10k_0402") (at 290.83 259.08 270) (unit 1)
    (in_bom yes) (on_board yes) (fields_autoplaced)
    (property "Reference" "R175" (id 0) (at 293.37 260.35 90)
      (effects (font (size 1.524 1.524)) (justify left))
    )
    (property "Value" "R_10k_0402" (id 1) (at 287.02 259.08 0)
      (effects (font (size 1.524 1.524)) hide)
    )
    (property "Footprint" "sa800u-baseboard-hw-footprints:R_0402_1005Metric" (id 2) (at 295.91 264.16 0)
      (effects (font (size 1.524 1.524)) (justify left) hide)
    )
    (property "Datasheet" "https://www.bourns.com/docs/product-datasheets/cr.pdf" (id 3) (at 290.83 259.08 0)
      (effects (font (size 1.27 1.27)) hide)
    )
    (property "Manufacturer" "Bourns" (id 4) (at 300.99 264.16 0)
      (effects (font (size 1.524 1.524)) (justify left) hide)
    )
    (property "MPN" "CR0402-FX-1002GLF" (id 5) (at 298.45 264.16 0)
      (effects (font (size 1.524 1.524)) (justify left) hide)
    )
    (property "Val" "10k" (id 6) (at 293.37 263.5249 90)
      (effects (font (size 1.27 1.27)) (justify left))
    )
    (property "DNP" "" (id 7) (at 292.608 261.5692 90)
      (effects (font (size 1.27 1.27)) (justify left) hide)
    )
    (property "License" "Apache-2.0" (id 8) (at 265.43 279.4 0)
      (effects (font (size 1.27 1.27) (thickness 0.15)) (justify left bottom) hide)
    )
    (property "Author" "Antmicro" (id 9) (at 262.89 279.4 0)
      (effects (font (size 1.27 1.27) (thickness 0.15)) (justify left bottom) hide)
    )
    (property "Tolerance" "1%" (id 10) (at 280.67 279.4 0)
      (effects (font (size 1.27 1.27)) (justify left bottom) hide)
    )
    (pin "1")
    (pin "2")
  )

  (symbol (lib_id "sa800u-baseboard-hw:R_0R_0402") (at 277.495 199.39 0) (unit 1)
    (in_bom yes) (on_board yes)
    (property "Reference" "R179" (id 0) (at 274.955 198.247 0)
      (effects (font (size 1.524 1.524)))
    )
    (property "Value" "R_0R_0402" (id 1) (at 277.495 203.2 0)
      (effects (font (size 1.524 1.524)) hide)
    )
    (property "Footprint" "sa800u-baseboard-hw-footprints:R_0402_1005Metric" (id 2) (at 282.575 194.31 0)
      (effects (font (size 1.524 1.524)) (justify left) hide)
    )
    (property "Datasheet" "https://industrial.panasonic.com/cdbs/www-data/pdf/RDA0000/AOA0000C301.pdf" (id 3) (at 277.495 199.39 0)
      (effects (font (size 1.27 1.27)) hide)
    )
    (property "Manufacturer" "Panasonic" (id 4) (at 282.575 189.23 0)
      (effects (font (size 1.524 1.524)) (justify left) hide)
    )
    (property "MPN" "ERJ2GE0R00X" (id 5) (at 282.575 191.77 0)
      (effects (font (size 1.524 1.524)) (justify left) hide)
    )
    (property "Val" "0R" (id 6) (at 283.591 198.374 0))
    (property "License" "Apache-2.0" (id 7) (at 297.815 224.79 0)
      (effects (font (size 1.27 1.27) (thickness 0.15)) (justify left bottom) hide)
    )
    (property "Author" "Antmicro" (id 8) (at 297.815 227.33 0)
      (effects (font (size 1.27 1.27) (thickness 0.15)) (justify left bottom) hide)
    )
    (property "Tolerance" "~" (id 9) (at 297.815 209.55 0)
      (effects (font (size 1.27 1.27)) (justify left bottom) hide)
    )
    (property "Current" "1A" (id 10) (at 297.815 229.87 0)
      (effects (font (size 1.27 1.27) (thickness 0.15)) (justify left bottom) hide)
    )
    (pin "1")
    (pin "2")
  )

  (symbol (lib_id "sa800u-baseboard-hw:R_4k7_0402") (at 316.611 104.267 90) (unit 1)
    (in_bom yes) (on_board yes) (fields_autoplaced)
    (property "Reference" "R71" (id 0) (at 319.151 100.457 90)
      (effects (font (size 1.524 1.524)) (justify right))
    )
    (property "Value" "R_4k7_0402" (id 1) (at 320.421 104.267 0)
      (effects (font (size 1.524 1.524)) hide)
    )
    (property "Footprint" "sa800u-baseboard-hw-footprints:R_0402_1005Metric" (id 2) (at 311.531 99.187 0)
      (effects (font (size 1.524 1.524)) (justify left) hide)
    )
    (property "Datasheet" "https://www.bourns.com/docs/product-datasheets/cr.pdf" (id 3) (at 316.611 104.267 0)
      (effects (font (size 1.27 1.27)) hide)
    )
    (property "Manufacturer" "Bourns" (id 4) (at 306.451 99.187 0)
      (effects (font (size 1.524 1.524)) (justify left) hide)
    )
    (property "MPN" "CR0402-FX-4701GLF" (id 5) (at 308.991 99.187 0)
      (effects (font (size 1.524 1.524)) (justify left) hide)
    )
    (property "Val" "4k7" (id 6) (at 319.151 103.6319 90)
      (effects (font (size 1.27 1.27)) (justify right))
    )
    (property "License" "Apache-2.0" (id 7) (at 342.011 83.947 0)
      (effects (font (size 1.27 1.27) (thickness 0.15)) (justify left bottom) hide)
    )
    (property "Author" "Antmicro" (id 8) (at 344.551 83.947 0)
      (effects (font (size 1.27 1.27) (thickness 0.15)) (justify left bottom) hide)
    )
    (property "Tolerance" "1%" (id 9) (at 326.771 83.947 0)
      (effects (font (size 1.27 1.27)) (justify left bottom) hide)
    )
    (pin "1")
    (pin "2")
  )

  (symbol (lib_id "sa800u-baseboard-hw:R_4k7_0402") (at 324.739 104.267 90) (unit 1)
    (in_bom yes) (on_board yes) (fields_autoplaced)
    (property "Reference" "R72" (id 0) (at 327.279 100.457 90)
      (effects (font (size 1.524 1.524)) (justify right))
    )
    (property "Value" "R_4k7_0402" (id 1) (at 328.549 104.267 0)
      (effects (font (size 1.524 1.524)) hide)
    )
    (property "Footprint" "sa800u-baseboard-hw-footprints:R_0402_1005Metric" (id 2) (at 319.659 99.187 0)
      (effects (font (size 1.524 1.524)) (justify left) hide)
    )
    (property "Datasheet" "https://www.bourns.com/docs/product-datasheets/cr.pdf" (id 3) (at 324.739 104.267 0)
      (effects (font (size 1.27 1.27)) hide)
    )
    (property "Manufacturer" "Bourns" (id 4) (at 314.579 99.187 0)
      (effects (font (size 1.524 1.524)) (justify left) hide)
    )
    (property "MPN" "CR0402-FX-4701GLF" (id 5) (at 317.119 99.187 0)
      (effects (font (size 1.524 1.524)) (justify left) hide)
    )
    (property "Val" "4k7" (id 6) (at 327.279 103.6319 90)
      (effects (font (size 1.27 1.27)) (justify right))
    )
    (property "License" "Apache-2.0" (id 7) (at 350.139 83.947 0)
      (effects (font (size 1.27 1.27) (thickness 0.15)) (justify left bottom) hide)
    )
    (property "Author" "Antmicro" (id 8) (at 352.679 83.947 0)
      (effects (font (size 1.27 1.27) (thickness 0.15)) (justify left bottom) hide)
    )
    (property "Tolerance" "1%" (id 9) (at 334.899 83.947 0)
      (effects (font (size 1.27 1.27)) (justify left bottom) hide)
    )
    (pin "1")
    (pin "2")
  )

  (symbol (lib_id "sa800u-baseboard-hw:PWR_FLAG") (at 198.755 194.31 180) (unit 1)
    (in_bom yes) (on_board yes) (fields_autoplaced)
    (property "Reference" "#FLG016" (id 0) (at 198.755 196.215 0)
      (effects (font (size 1.27 1.27)) hide)
    )
    (property "Value" "PWR_FLAG" (id 1) (at 198.755 199.39 0))
    (property "Footprint" "" (id 2) (at 198.755 194.31 0)
      (effects (font (size 1.27 1.27)) hide)
    )
    (property "Datasheet" "~" (id 3) (at 198.755 194.31 0)
      (effects (font (size 1.27 1.27)) hide)
    )
    (pin "1")
  )

  (symbol (lib_id "sa800u-baseboard-hw:PESD2V5Y1BSFYL") (at 368.427 62.103 90) (mirror x) (unit 1)
    (in_bom yes) (on_board yes) (fields_autoplaced)
    (property "Reference" "D17" (id 0) (at 371.602 66.548 90)
      (effects (font (size 1.524 1.524)) (justify right))
    )
    (property "Value" "PESD2V5Y1BSFYL" (id 1) (at 371.602 69.7229 90)
      (effects (font (size 1.27 1.27)) (justify right))
    )
    (property "Footprint" "sa800u-baseboard-hw-footprints:D_0201_0603Metric" (id 2) (at 379.857 62.103 0)
      (effects (font (size 1.27 1.27)) (justify left) hide)
    )
    (property "Datasheet" "https://assets.nexperia.com/documents/data-sheet/PESD2V5Y1BSF.pdf" (id 3) (at 372.237 67.437 0)
      (effects (font (size 1.27 1.27)) hide)
    )
    (property "Manufacturer" "Nexperia" (id 4) (at 383.032 62.103 0)
      (effects (font (size 1.27 1.27)) (justify left) hide)
    )
    (property "MPN" "PESD2V5Y1BSFYL" (id 5) (at 376.682 62.103 0)
      (effects (font (size 1.27 1.27)) (justify left) hide)
    )
    (property "Author" "Antmicro" (id 6) (at 388.747 87.503 0)
      (effects (font (size 1.27 1.27) (thickness 0.15)) (justify left bottom) hide)
    )
    (property "License" "Apache-2.0" (id 7) (at 391.287 87.503 0)
      (effects (font (size 1.27 1.27) (thickness 0.15)) (justify left bottom) hide)
    )
    (pin "1")
    (pin "2")
  )

  (symbol (lib_id "sa800u-baseboard-hw:GND") (at 368.427 74.168 0) (mirror y) (unit 1)
    (in_bom yes) (on_board yes) (fields_autoplaced)
    (property "Reference" "#PWR0161" (id 0) (at 368.427 80.518 0)
      (effects (font (size 1.27 1.27)) hide)
    )
    (property "Value" "GND" (id 1) (at 368.427 79.248 0))
    (property "Footprint" "" (id 2) (at 368.427 74.168 0)
      (effects (font (size 1.27 1.27)) hide)
    )
    (property "Datasheet" "" (id 3) (at 368.427 74.168 0)
      (effects (font (size 1.27 1.27)) hide)
    )
    (property "Author" "Antmicro" (id 4) (at 359.537 81.788 0)
      (effects (font (size 1.27 1.27) (thickness 0.15)) (justify left bottom) hide)
    )
    (property "License" "Apache-2.0" (id 5) (at 359.537 84.328 0)
      (effects (font (size 1.27 1.27) (thickness 0.15)) (justify left bottom) hide)
    )
    (pin "1")
  )

  (symbol (lib_id "sa800u-baseboard-hw:PESD2V5Y1BSFYL") (at 368.427 91.313 90) (mirror x) (unit 1)
    (in_bom yes) (on_board yes) (fields_autoplaced)
    (property "Reference" "D18" (id 0) (at 371.602 95.758 90)
      (effects (font (size 1.524 1.524)) (justify right))
    )
    (property "Value" "PESD2V5Y1BSFYL" (id 1) (at 371.602 98.9329 90)
      (effects (font (size 1.27 1.27)) (justify right))
    )
    (property "Footprint" "sa800u-baseboard-hw-footprints:D_0201_0603Metric" (id 2) (at 379.857 91.313 0)
      (effects (font (size 1.27 1.27)) (justify left) hide)
    )
    (property "Datasheet" "https://assets.nexperia.com/documents/data-sheet/PESD2V5Y1BSF.pdf" (id 3) (at 372.237 96.647 0)
      (effects (font (size 1.27 1.27)) hide)
    )
    (property "Manufacturer" "Nexperia" (id 4) (at 383.032 91.313 0)
      (effects (font (size 1.27 1.27)) (justify left) hide)
    )
    (property "MPN" "PESD2V5Y1BSFYL" (id 5) (at 376.682 91.313 0)
      (effects (font (size 1.27 1.27)) (justify left) hide)
    )
    (property "Author" "Antmicro" (id 6) (at 388.747 116.713 0)
      (effects (font (size 1.27 1.27) (thickness 0.15)) (justify left bottom) hide)
    )
    (property "License" "Apache-2.0" (id 7) (at 391.287 116.713 0)
      (effects (font (size 1.27 1.27) (thickness 0.15)) (justify left bottom) hide)
    )
    (pin "1")
    (pin "2")
  )

  (symbol (lib_id "sa800u-baseboard-hw:GND") (at 368.427 103.378 0) (mirror y) (unit 1)
    (in_bom yes) (on_board yes) (fields_autoplaced)
    (property "Reference" "#PWR0162" (id 0) (at 368.427 109.728 0)
      (effects (font (size 1.27 1.27)) hide)
    )
    (property "Value" "GND" (id 1) (at 368.427 108.458 0))
    (property "Footprint" "" (id 2) (at 368.427 103.378 0)
      (effects (font (size 1.27 1.27)) hide)
    )
    (property "Datasheet" "" (id 3) (at 368.427 103.378 0)
      (effects (font (size 1.27 1.27)) hide)
    )
    (property "Author" "Antmicro" (id 4) (at 359.537 110.998 0)
      (effects (font (size 1.27 1.27) (thickness 0.15)) (justify left bottom) hide)
    )
    (property "License" "Apache-2.0" (id 5) (at 359.537 113.538 0)
      (effects (font (size 1.27 1.27) (thickness 0.15)) (justify left bottom) hide)
    )
    (pin "1")
  )

  (symbol (lib_id "sa800u-baseboard-hw:R_0R_0402") (at 277.495 196.85 0) (unit 1)
    (in_bom yes) (on_board yes)
    (property "Reference" "R178" (id 0) (at 274.955 195.58 0)
      (effects (font (size 1.524 1.524)))
    )
    (property "Value" "R_0R_0402" (id 1) (at 277.495 200.66 0)
      (effects (font (size 1.524 1.524)) hide)
    )
    (property "Footprint" "sa800u-baseboard-hw-footprints:R_0402_1005Metric" (id 2) (at 282.575 191.77 0)
      (effects (font (size 1.524 1.524)) (justify left) hide)
    )
    (property "Datasheet" "https://industrial.panasonic.com/cdbs/www-data/pdf/RDA0000/AOA0000C301.pdf" (id 3) (at 277.495 196.85 0)
      (effects (font (size 1.27 1.27)) hide)
    )
    (property "Manufacturer" "Panasonic" (id 4) (at 282.575 186.69 0)
      (effects (font (size 1.524 1.524)) (justify left) hide)
    )
    (property "MPN" "ERJ2GE0R00X" (id 5) (at 282.575 189.23 0)
      (effects (font (size 1.524 1.524)) (justify left) hide)
    )
    (property "Val" "0R" (id 6) (at 283.464 195.834 0))
    (property "License" "Apache-2.0" (id 7) (at 297.815 222.25 0)
      (effects (font (size 1.27 1.27) (thickness 0.15)) (justify left bottom) hide)
    )
    (property "Author" "Antmicro" (id 8) (at 297.815 224.79 0)
      (effects (font (size 1.27 1.27) (thickness 0.15)) (justify left bottom) hide)
    )
    (property "Tolerance" "~" (id 9) (at 297.815 207.01 0)
      (effects (font (size 1.27 1.27)) (justify left bottom) hide)
    )
    (property "Current" "1A" (id 10) (at 297.815 227.33 0)
      (effects (font (size 1.27 1.27) (thickness 0.15)) (justify left bottom) hide)
    )
    (pin "1")
    (pin "2")
  )

  (symbol (lib_id "sa800u-baseboard-hw:GND") (at 368.427 131.318 0) (mirror y) (unit 1)
    (in_bom yes) (on_board yes) (fields_autoplaced)
    (property "Reference" "#PWR0163" (id 0) (at 368.427 137.668 0)
      (effects (font (size 1.27 1.27)) hide)
    )
    (property "Value" "GND" (id 1) (at 368.427 136.398 0))
    (property "Footprint" "" (id 2) (at 368.427 131.318 0)
      (effects (font (size 1.27 1.27)) hide)
    )
    (property "Datasheet" "" (id 3) (at 368.427 131.318 0)
      (effects (font (size 1.27 1.27)) hide)
    )
    (property "Author" "Antmicro" (id 4) (at 359.537 138.938 0)
      (effects (font (size 1.27 1.27) (thickness 0.15)) (justify left bottom) hide)
    )
    (property "License" "Apache-2.0" (id 5) (at 359.537 141.478 0)
      (effects (font (size 1.27 1.27) (thickness 0.15)) (justify left bottom) hide)
    )
    (pin "1")
  )

  (symbol (lib_id "sa800u-baseboard-hw:PESD2V5Y1BSFYL") (at 368.427 119.253 90) (mirror x) (unit 1)
    (in_bom yes) (on_board yes) (fields_autoplaced)
    (property "Reference" "D19" (id 0) (at 371.602 123.698 90)
      (effects (font (size 1.524 1.524)) (justify right))
    )
    (property "Value" "PESD2V5Y1BSFYL" (id 1) (at 371.602 126.8729 90)
      (effects (font (size 1.27 1.27)) (justify right))
    )
    (property "Footprint" "sa800u-baseboard-hw-footprints:D_0201_0603Metric" (id 2) (at 379.857 119.253 0)
      (effects (font (size 1.27 1.27)) (justify left) hide)
    )
    (property "Datasheet" "https://assets.nexperia.com/documents/data-sheet/PESD2V5Y1BSF.pdf" (id 3) (at 372.237 124.587 0)
      (effects (font (size 1.27 1.27)) hide)
    )
    (property "Manufacturer" "Nexperia" (id 4) (at 383.032 119.253 0)
      (effects (font (size 1.27 1.27)) (justify left) hide)
    )
    (property "MPN" "PESD2V5Y1BSFYL" (id 5) (at 376.682 119.253 0)
      (effects (font (size 1.27 1.27)) (justify left) hide)
    )
    (property "Author" "Antmicro" (id 6) (at 388.747 144.653 0)
      (effects (font (size 1.27 1.27) (thickness 0.15)) (justify left bottom) hide)
    )
    (property "License" "Apache-2.0" (id 7) (at 391.287 144.653 0)
      (effects (font (size 1.27 1.27) (thickness 0.15)) (justify left bottom) hide)
    )
    (pin "1")
    (pin "2")
  )

  (symbol (lib_id "sa800u-baseboard-hw:GND") (at 369.697 159.258 0) (mirror y) (unit 1)
    (in_bom yes) (on_board yes) (fields_autoplaced)
    (property "Reference" "#PWR0164" (id 0) (at 369.697 165.608 0)
      (effects (font (size 1.27 1.27)) hide)
    )
    (property "Value" "GND" (id 1) (at 369.697 164.338 0))
    (property "Footprint" "" (id 2) (at 369.697 159.258 0)
      (effects (font (size 1.27 1.27)) hide)
    )
    (property "Datasheet" "" (id 3) (at 369.697 159.258 0)
      (effects (font (size 1.27 1.27)) hide)
    )
    (property "Author" "Antmicro" (id 4) (at 360.807 166.878 0)
      (effects (font (size 1.27 1.27) (thickness 0.15)) (justify left bottom) hide)
    )
    (property "License" "Apache-2.0" (id 5) (at 360.807 169.418 0)
      (effects (font (size 1.27 1.27) (thickness 0.15)) (justify left bottom) hide)
    )
    (pin "1")
  )

  (symbol (lib_id "sa800u-baseboard-hw:PESD2V5Y1BSFYL") (at 369.697 147.193 90) (mirror x) (unit 1)
    (in_bom yes) (on_board yes) (fields_autoplaced)
    (property "Reference" "D20" (id 0) (at 372.872 151.638 90)
      (effects (font (size 1.524 1.524)) (justify right))
    )
    (property "Value" "PESD2V5Y1BSFYL" (id 1) (at 372.872 154.8129 90)
      (effects (font (size 1.27 1.27)) (justify right))
    )
    (property "Footprint" "sa800u-baseboard-hw-footprints:D_0201_0603Metric" (id 2) (at 381.127 147.193 0)
      (effects (font (size 1.27 1.27)) (justify left) hide)
    )
    (property "Datasheet" "https://assets.nexperia.com/documents/data-sheet/PESD2V5Y1BSF.pdf" (id 3) (at 373.507 152.527 0)
      (effects (font (size 1.27 1.27)) hide)
    )
    (property "Manufacturer" "Nexperia" (id 4) (at 384.302 147.193 0)
      (effects (font (size 1.27 1.27)) (justify left) hide)
    )
    (property "MPN" "PESD2V5Y1BSFYL" (id 5) (at 377.952 147.193 0)
      (effects (font (size 1.27 1.27)) (justify left) hide)
    )
    (property "Author" "Antmicro" (id 6) (at 390.017 172.593 0)
      (effects (font (size 1.27 1.27) (thickness 0.15)) (justify left bottom) hide)
    )
    (property "License" "Apache-2.0" (id 7) (at 392.557 172.593 0)
      (effects (font (size 1.27 1.27) (thickness 0.15)) (justify left bottom) hide)
    )
    (pin "1")
    (pin "2")
  )

  (symbol (lib_id "sa800u-baseboard-hw:R_0R_0402") (at 277.495 194.31 0) (unit 1)
    (in_bom yes) (on_board yes)
    (property "Reference" "R177" (id 0) (at 274.955 193.167 0)
      (effects (font (size 1.524 1.524)))
    )
    (property "Value" "R_0R_0402" (id 1) (at 277.495 198.12 0)
      (effects (font (size 1.524 1.524)) hide)
    )
    (property "Footprint" "sa800u-baseboard-hw-footprints:R_0402_1005Metric" (id 2) (at 282.575 189.23 0)
      (effects (font (size 1.524 1.524)) (justify left) hide)
    )
    (property "Datasheet" "https://industrial.panasonic.com/cdbs/www-data/pdf/RDA0000/AOA0000C301.pdf" (id 3) (at 277.495 194.31 0)
      (effects (font (size 1.27 1.27)) hide)
    )
    (property "Manufacturer" "Panasonic" (id 4) (at 282.575 184.15 0)
      (effects (font (size 1.524 1.524)) (justify left) hide)
    )
    (property "MPN" "ERJ2GE0R00X" (id 5) (at 282.575 186.69 0)
      (effects (font (size 1.524 1.524)) (justify left) hide)
    )
    (property "Val" "0R" (id 6) (at 283.464 193.294 0))
    (property "License" "Apache-2.0" (id 7) (at 297.815 219.71 0)
      (effects (font (size 1.27 1.27) (thickness 0.15)) (justify left bottom) hide)
    )
    (property "Author" "Antmicro" (id 8) (at 297.815 222.25 0)
      (effects (font (size 1.27 1.27) (thickness 0.15)) (justify left bottom) hide)
    )
    (property "Tolerance" "~" (id 9) (at 297.815 204.47 0)
      (effects (font (size 1.27 1.27)) (justify left bottom) hide)
    )
    (property "Current" "1A" (id 10) (at 297.815 224.79 0)
      (effects (font (size 1.27 1.27) (thickness 0.15)) (justify left bottom) hide)
    )
    (pin "1")
    (pin "2")
  )

  (symbol (lib_id "sa800u-baseboard-hw:R_0R_0402") (at 277.495 191.77 0) (unit 1)
    (in_bom yes) (on_board yes)
    (property "Reference" "R176" (id 0) (at 275.082 190.627 0)
      (effects (font (size 1.524 1.524)))
    )
    (property "Value" "R_0R_0402" (id 1) (at 277.495 195.58 0)
      (effects (font (size 1.524 1.524)) hide)
    )
    (property "Footprint" "sa800u-baseboard-hw-footprints:R_0402_1005Metric" (id 2) (at 282.575 186.69 0)
      (effects (font (size 1.524 1.524)) (justify left) hide)
    )
    (property "Datasheet" "https://industrial.panasonic.com/cdbs/www-data/pdf/RDA0000/AOA0000C301.pdf" (id 3) (at 277.495 191.77 0)
      (effects (font (size 1.27 1.27)) hide)
    )
    (property "Manufacturer" "Panasonic" (id 4) (at 282.575 181.61 0)
      (effects (font (size 1.524 1.524)) (justify left) hide)
    )
    (property "MPN" "ERJ2GE0R00X" (id 5) (at 282.575 184.15 0)
      (effects (font (size 1.524 1.524)) (justify left) hide)
    )
    (property "Val" "0R" (id 6) (at 283.464 190.627 0))
    (property "License" "Apache-2.0" (id 7) (at 297.815 217.17 0)
      (effects (font (size 1.27 1.27) (thickness 0.15)) (justify left bottom) hide)
    )
    (property "Author" "Antmicro" (id 8) (at 297.815 219.71 0)
      (effects (font (size 1.27 1.27) (thickness 0.15)) (justify left bottom) hide)
    )
    (property "Tolerance" "~" (id 9) (at 297.815 201.93 0)
      (effects (font (size 1.27 1.27)) (justify left bottom) hide)
    )
    (property "Current" "1A" (id 10) (at 297.815 222.25 0)
      (effects (font (size 1.27 1.27) (thickness 0.15)) (justify left bottom) hide)
    )
    (pin "1")
    (pin "2")
  )

  (symbol (lib_id "sa800u-baseboard-hw:GND") (at 316.23 181.61 0) (unit 1)
    (in_bom yes) (on_board yes) (fields_autoplaced)
    (property "Reference" "#PWR0160" (id 0) (at 316.23 187.96 0)
      (effects (font (size 1.27 1.27)) hide)
    )
    (property "Value" "GND" (id 1) (at 316.23 186.69 0))
    (property "Footprint" "" (id 2) (at 316.23 181.61 0)
      (effects (font (size 1.27 1.27)) hide)
    )
    (property "Datasheet" "" (id 3) (at 316.23 181.61 0)
      (effects (font (size 1.27 1.27)) hide)
    )
    (property "Author" "Antmicro" (id 4) (at 325.12 189.23 0)
      (effects (font (size 1.27 1.27) (thickness 0.15)) (justify left bottom) hide)
    )
    (property "License" "Apache-2.0" (id 5) (at 325.12 191.77 0)
      (effects (font (size 1.27 1.27) (thickness 0.15)) (justify left bottom) hide)
    )
    (pin "1")
  )

  (symbol (lib_id "sa800u-baseboard-hw:GND") (at 286.385 200.66 0) (unit 1)
    (in_bom yes) (on_board yes) (fields_autoplaced)
    (property "Reference" "#PWR0271" (id 0) (at 286.385 207.01 0)
      (effects (font (size 1.27 1.27)) hide)
    )
    (property "Value" "GND" (id 1) (at 286.385 205.74 0))
    (property "Footprint" "" (id 2) (at 286.385 200.66 0)
      (effects (font (size 1.27 1.27)) hide)
    )
    (property "Datasheet" "" (id 3) (at 286.385 200.66 0)
      (effects (font (size 1.27 1.27)) hide)
    )
    (property "Author" "Antmicro" (id 4) (at 295.275 208.28 0)
      (effects (font (size 1.27 1.27) (thickness 0.15)) (justify left bottom) hide)
    )
    (property "License" "Apache-2.0" (id 5) (at 295.275 210.82 0)
      (effects (font (size 1.27 1.27) (thickness 0.15)) (justify left bottom) hide)
    )
    (pin "1")
  )

  (symbol (lib_id "sa800u-baseboard-hw:PMEG3050EP,115") (at 28.829 187.96 0) (unit 1)
    (in_bom yes) (on_board yes)
    (property "Reference" "D38" (id 0) (at 31.623 182.626 0)
      (effects (font (size 1.524 1.524)))
    )
    (property "Value" "PMEG3050EP,115" (id 1) (at 31.6865 184.785 0)
      (effects (font (size 1.524 1.524)))
    )
    (property "Footprint" "sa800u-baseboard-hw-footprints:Nexperia_SOD128" (id 2) (at 33.909 182.88 0)
      (effects (font (size 1.524 1.524)) (justify left) hide)
    )
    (property "Datasheet" "https://www.mouser.pl/datasheet/2/916/PMEG3050EP-2938519.pdf" (id 3) (at 33.909 180.34 0)
      (effects (font (size 1.524 1.524)) (justify left) hide)
    )
    (property "MPN" "PMEG3050EP,115" (id 4) (at 33.909 175.26 0)
      (effects (font (size 1.524 1.524)) (justify left) hide)
    )
    (property "Manufacturer" "Nexperia" (id 5) (at 33.909 160.02 0)
      (effects (font (size 1.524 1.524)) (justify left) hide)
    )
    (property "Author" "Antmicro" (id 6) (at 50.419 208.28 0)
      (effects (font (size 1.27 1.27) (thickness 0.15)) (justify left bottom) hide)
    )
    (property "License" "Apache-2.0" (id 7) (at 50.419 210.82 0)
      (effects (font (size 1.27 1.27) (thickness 0.15)) (justify left bottom) hide)
    )
    (pin "1")
    (pin "2")
  )

  (symbol (lib_id "sa800u-baseboard-hw:TP_0.75mm_SMD") (at 99.314 247.269 90) (unit 1)
    (in_bom yes) (on_board yes) (fields_autoplaced)
    (property "Reference" "TP112" (id 0) (at 101.092 244.0939 90)
      (effects (font (size 1.27 1.27)) (justify right))
    )
    (property "Value" "TP_0.75mm_SMD" (id 1) (at 99.314 247.269 0)
      (effects (font (size 1.27 1.27)) hide)
    )
    (property "Footprint" "sa800u-baseboard-hw-footprints:TP_SMD_0.75mm" (id 2) (at 99.314 247.269 0)
      (effects (font (size 1.27 1.27)) hide)
    )
    (property "Datasheet" "" (id 3) (at 99.314 247.269 0)
      (effects (font (size 1.27 1.27)) hide)
    )
    (property "MPN" "" (id 4) (at 114.554 229.489 0)
      (effects (font (size 1.27 1.27) (thickness 0.15)) (justify left bottom) hide)
    )
    (property "Manufacturer" "" (id 5) (at 117.094 229.489 0)
      (effects (font (size 1.27 1.27) (thickness 0.15)) (justify left bottom) hide)
    )
    (property "Author" "Antmicro" (id 6) (at 119.634 229.489 0)
      (effects (font (size 1.27 1.27) (thickness 0.15)) (justify left bottom) hide)
    )
    (property "License" "Apache-2.0" (id 7) (at 122.174 229.489 0)
      (effects (font (size 1.27 1.27) (thickness 0.15)) (justify left bottom) hide)
    )
    (pin "1")
  )

  (symbol (lib_id "sa800u-baseboard-hw:SW_CVS-02B") (at 274.32 265.43 0) (unit 1)
    (in_bom yes) (on_board yes) (fields_autoplaced)
    (property "Reference" "SW1" (id 0) (at 280.67 257.81 0))
    (property "Value" "SW_CVS-02B" (id 1) (at 274.32 269.24 0)
      (effects (font (size 1.27 1.27)) hide)
    )
    (property "Footprint" "sa800u-baseboard-hw-footprints:SW_DIP_SPSTx02_Slide_Copal_CVS-02xB_W5.9mm_P1mm" (id 2) (at 274.32 276.86 0)
      (effects (font (size 1.27 1.27)) hide)
    )
    (property "Datasheet" "https://www.mouser.pl/datasheet/2/972/cvs-1827291.pdf" (id 3) (at 274.32 265.43 0)
      (effects (font (size 1.27 1.27)) hide)
    )
    (property "MPN" "CVS-02B" (id 4) (at 280.67 260.35 0))
    (property "Manufacturer" "Nidec" (id 5) (at 274.32 274.32 0)
      (effects (font (size 1.27 1.27)) hide)
    )
    (property "Author" "Antmicro" (id 6) (at 300.99 283.21 0)
      (effects (font (size 1.27 1.27) (thickness 0.15)) (justify left bottom) hide)
    )
    (property "License" "Apache-2.0" (id 7) (at 300.99 285.75 0)
      (effects (font (size 1.27 1.27) (thickness 0.15)) (justify left bottom) hide)
    )
    (pin "1")
    (pin "2")
    (pin "3")
    (pin "4")
    (pin "SH")
  )

  (symbol (lib_id "sa800u-baseboard-hw:PWR_FLAG") (at 199.39 181.61 0) (unit 1)
    (in_bom yes) (on_board yes) (fields_autoplaced)
    (property "Reference" "#FLG018" (id 0) (at 199.39 179.705 0)
      (effects (font (size 1.27 1.27)) hide)
    )
    (property "Value" "PWR_FLAG" (id 1) (at 199.39 176.53 0))
    (property "Footprint" "" (id 2) (at 199.39 181.61 0)
      (effects (font (size 1.27 1.27)) hide)
    )
    (property "Datasheet" "~" (id 3) (at 199.39 181.61 0)
      (effects (font (size 1.27 1.27)) hide)
    )
    (pin "1")
  )

  (symbol (lib_id "sa800u-baseboard-hw:PWR_FLAG") (at 199.39 184.15 180) (unit 1)
    (in_bom yes) (on_board yes) (fields_autoplaced)
    (property "Reference" "#FLG019" (id 0) (at 199.39 186.055 0)
      (effects (font (size 1.27 1.27)) hide)
    )
    (property "Value" "PWR_FLAG" (id 1) (at 199.39 189.23 0))
    (property "Footprint" "" (id 2) (at 199.39 184.15 0)
      (effects (font (size 1.27 1.27)) hide)
    )
    (property "Datasheet" "~" (id 3) (at 199.39 184.15 0)
      (effects (font (size 1.27 1.27)) hide)
    )
    (pin "1")
  )

  (symbol (lib_id "sa800u-baseboard-hw:PWR_FLAG") (at 185.547 161.925 0) (unit 1)
    (in_bom yes) (on_board yes) (fields_autoplaced)
    (property "Reference" "#FLG017" (id 0) (at 185.547 160.02 0)
      (effects (font (size 1.27 1.27)) hide)
    )
    (property "Value" "PWR_FLAG" (id 1) (at 185.547 156.845 0))
    (property "Footprint" "" (id 2) (at 185.547 161.925 0)
      (effects (font (size 1.27 1.27)) hide)
    )
    (property "Datasheet" "~" (id 3) (at 185.547 161.925 0)
      (effects (font (size 1.27 1.27)) hide)
    )
    (pin "1")
  )

  (symbol (lib_id "sa800u-baseboard-hw:PWR_FLAG") (at 116.84 165.1 0) (unit 1)
    (in_bom yes) (on_board yes) (fields_autoplaced)
    (property "Reference" "#FLG014" (id 0) (at 116.84 163.195 0)
      (effects (font (size 1.27 1.27)) hide)
    )
    (property "Value" "PWR_FLAG" (id 1) (at 116.84 159.385 0))
    (property "Footprint" "" (id 2) (at 116.84 165.1 0)
      (effects (font (size 1.27 1.27)) hide)
    )
    (property "Datasheet" "~" (id 3) (at 116.84 165.1 0)
      (effects (font (size 1.27 1.27)) hide)
    )
    (pin "1")
  )

  (symbol (lib_id "sa800u-baseboard-hw:PWR_FLAG") (at 116.84 167.64 180) (unit 1)
    (in_bom yes) (on_board yes) (fields_autoplaced)
    (property "Reference" "#FLG015" (id 0) (at 116.84 169.545 0)
      (effects (font (size 1.27 1.27)) hide)
    )
    (property "Value" "PWR_FLAG" (id 1) (at 116.84 172.085 0))
    (property "Footprint" "" (id 2) (at 116.84 167.64 0)
      (effects (font (size 1.27 1.27)) hide)
    )
    (property "Datasheet" "~" (id 3) (at 116.84 167.64 0)
      (effects (font (size 1.27 1.27)) hide)
    )
    (pin "1")
  )

  (symbol (lib_id "sa800u-baseboard-hw:GND") (at 393.827 93.853 0) (mirror y) (unit 1)
    (in_bom yes) (on_board yes) (fields_autoplaced)
    (property "Reference" "#PWR0169" (id 0) (at 393.827 100.203 0)
      (effects (font (size 1.27 1.27)) hide)
    )
    (property "Value" "GND" (id 1) (at 393.827 98.298 0))
    (property "Footprint" "" (id 2) (at 393.827 93.853 0)
      (effects (font (size 1.27 1.27)) hide)
    )
    (property "Datasheet" "" (id 3) (at 393.827 93.853 0)
      (effects (font (size 1.27 1.27)) hide)
    )
    (property "Author" "Antmicro" (id 4) (at 384.937 101.473 0)
      (effects (font (size 1.27 1.27) (thickness 0.15)) (justify left bottom) hide)
    )
    (property "License" "Apache-2.0" (id 5) (at 384.937 104.013 0)
      (effects (font (size 1.27 1.27) (thickness 0.15)) (justify left bottom) hide)
    )
    (pin "1")
  )

  (symbol (lib_id "sa800u-baseboard-hw:GND") (at 393.827 121.793 0) (mirror y) (unit 1)
    (in_bom yes) (on_board yes) (fields_autoplaced)
    (property "Reference" "#PWR0170" (id 0) (at 393.827 128.143 0)
      (effects (font (size 1.27 1.27)) hide)
    )
    (property "Value" "GND" (id 1) (at 393.827 126.238 0))
    (property "Footprint" "" (id 2) (at 393.827 121.793 0)
      (effects (font (size 1.27 1.27)) hide)
    )
    (property "Datasheet" "" (id 3) (at 393.827 121.793 0)
      (effects (font (size 1.27 1.27)) hide)
    )
    (property "Author" "Antmicro" (id 4) (at 384.937 129.413 0)
      (effects (font (size 1.27 1.27) (thickness 0.15)) (justify left bottom) hide)
    )
    (property "License" "Apache-2.0" (id 5) (at 384.937 131.953 0)
      (effects (font (size 1.27 1.27) (thickness 0.15)) (justify left bottom) hide)
    )
    (pin "1")
  )

  (symbol (lib_id "sa800u-baseboard-hw:GND") (at 395.097 149.733 0) (mirror y) (unit 1)
    (in_bom yes) (on_board yes) (fields_autoplaced)
    (property "Reference" "#PWR0171" (id 0) (at 395.097 156.083 0)
      (effects (font (size 1.27 1.27)) hide)
    )
    (property "Value" "GND" (id 1) (at 395.097 154.178 0))
    (property "Footprint" "" (id 2) (at 395.097 149.733 0)
      (effects (font (size 1.27 1.27)) hide)
    )
    (property "Datasheet" "" (id 3) (at 395.097 149.733 0)
      (effects (font (size 1.27 1.27)) hide)
    )
    (property "Author" "Antmicro" (id 4) (at 386.207 157.353 0)
      (effects (font (size 1.27 1.27) (thickness 0.15)) (justify left bottom) hide)
    )
    (property "License" "Apache-2.0" (id 5) (at 386.207 159.893 0)
      (effects (font (size 1.27 1.27) (thickness 0.15)) (justify left bottom) hide)
    )
    (pin "1")
  )

  (symbol (lib_id "sa800u-baseboard-hw:LED_G_0603_KP-1608ZGC") (at 371.475 181.61 0) (unit 1)
    (in_bom yes) (on_board yes) (fields_autoplaced)
    (property "Reference" "D15" (id 0) (at 375.285 177.8 0)
      (effects (font (size 1.524 1.524)))
    )
    (property "Value" "KP-1608EC" (id 1) (at 370.205 175.7426 0)
      (effects (font (size 1.524 1.524)) hide)
    )
    (property "Footprint" "sa800u-baseboard-hw-footprints:LED_0603_1608Metric_G" (id 2) (at 394.335 191.77 0)
      (effects (font (size 1.27 1.27) (thickness 0.15)) (justify left bottom) hide)
    )
    (property "Datasheet" "https://www.farnell.com/datasheets/2045914.pdf" (id 3) (at 394.335 194.31 0)
      (effects (font (size 1.27 1.27) (thickness 0.15)) (justify left bottom) hide)
    )
    (property "MPN" "KP-1608ZGC" (id 4) (at 394.335 196.85 0)
      (effects (font (size 1.27 1.27) (thickness 0.15)) (justify left bottom) hide)
    )
    (property "Manufacturer" "Kingbright" (id 5) (at 394.335 199.39 0)
      (effects (font (size 1.27 1.27) (thickness 0.15)) (justify left bottom) hide)
    )
    (property "Author" "Antmicro" (id 6) (at 394.335 201.93 0)
      (effects (font (size 1.27 1.27) (thickness 0.15)) (justify left bottom) hide)
    )
    (property "License" "Apache-2.0" (id 7) (at 394.335 204.47 0)
      (effects (font (size 1.27 1.27) (thickness 0.15)) (justify left bottom) hide)
    )
    (pin "1")
    (pin "2")
  )

  (symbol (lib_id "sa800u-baseboard-hw:R_10k_0402") (at 386.08 181.61 180) (unit 1)
    (in_bom yes) (on_board yes) (fields_autoplaced)
    (property "Reference" "R78" (id 0) (at 383.54 175.26 0)
      (effects (font (size 1.524 1.524)))
    )
    (property "Value" "R_10k_0402" (id 1) (at 386.08 177.8 0)
      (effects (font (size 1.524 1.524)) hide)
    )
    (property "Footprint" "sa800u-baseboard-hw-footprints:R_0402_1005Metric" (id 2) (at 381 186.69 0)
      (effects (font (size 1.524 1.524)) (justify left) hide)
    )
    (property "Datasheet" "https://www.bourns.com/docs/product-datasheets/cr.pdf" (id 3) (at 386.08 181.61 0)
      (effects (font (size 1.27 1.27)) hide)
    )
    (property "Manufacturer" "Bourns" (id 4) (at 381 191.77 0)
      (effects (font (size 1.524 1.524)) (justify left) hide)
    )
    (property "MPN" "CR0402-FX-1002GLF" (id 5) (at 381 189.23 0)
      (effects (font (size 1.524 1.524)) (justify left) hide)
    )
    (property "Val" "10k" (id 6) (at 383.54 177.8 0))
    (property "License" "Apache-2.0" (id 7) (at 365.76 156.21 0)
      (effects (font (size 1.27 1.27) (thickness 0.15)) (justify left bottom) hide)
    )
    (property "Author" "Antmicro" (id 8) (at 365.76 153.67 0)
      (effects (font (size 1.27 1.27) (thickness 0.15)) (justify left bottom) hide)
    )
    (property "Tolerance" "1%" (id 9) (at 365.76 171.45 0)
      (effects (font (size 1.27 1.27)) (justify left bottom) hide)
    )
    (pin "1")
    (pin "2")
  )

  (symbol (lib_id "sa800u-baseboard-hw:GND") (at 387.985 195.58 0) (unit 1)
    (in_bom yes) (on_board yes) (fields_autoplaced)
    (property "Reference" "#PWR0166" (id 0) (at 387.985 201.93 0)
      (effects (font (size 1.27 1.27)) hide)
    )
    (property "Value" "GND" (id 1) (at 387.985 200.66 0))
    (property "Footprint" "" (id 2) (at 387.985 195.58 0)
      (effects (font (size 1.27 1.27)) hide)
    )
    (property "Datasheet" "" (id 3) (at 387.985 195.58 0)
      (effects (font (size 1.27 1.27)) hide)
    )
    (property "Author" "Antmicro" (id 4) (at 396.875 203.2 0)
      (effects (font (size 1.27 1.27) (thickness 0.15)) (justify left bottom) hide)
    )
    (property "License" "Apache-2.0" (id 5) (at 396.875 205.74 0)
      (effects (font (size 1.27 1.27) (thickness 0.15)) (justify left bottom) hide)
    )
    (pin "1")
  )

  (symbol (lib_id "sa800u-baseboard-hw:LED_G_0603_KP-1608ZGC") (at 370.84 206.375 0) (unit 1)
    (in_bom yes) (on_board yes) (fields_autoplaced)
    (property "Reference" "D14" (id 0) (at 374.65 210.82 0)
      (effects (font (size 1.524 1.524)))
    )
    (property "Value" "KP-1608EC" (id 1) (at 369.57 200.5076 0)
      (effects (font (size 1.524 1.524)) hide)
    )
    (property "Footprint" "sa800u-baseboard-hw-footprints:LED_0603_1608Metric_G" (id 2) (at 393.7 216.535 0)
      (effects (font (size 1.27 1.27) (thickness 0.15)) (justify left bottom) hide)
    )
    (property "Datasheet" "https://www.farnell.com/datasheets/2045914.pdf" (id 3) (at 393.7 219.075 0)
      (effects (font (size 1.27 1.27) (thickness 0.15)) (justify left bottom) hide)
    )
    (property "MPN" "KP-1608ZGC" (id 4) (at 393.7 221.615 0)
      (effects (font (size 1.27 1.27) (thickness 0.15)) (justify left bottom) hide)
    )
    (property "Manufacturer" "Kingbright" (id 5) (at 393.7 224.155 0)
      (effects (font (size 1.27 1.27) (thickness 0.15)) (justify left bottom) hide)
    )
    (property "Author" "Antmicro" (id 6) (at 393.7 226.695 0)
      (effects (font (size 1.27 1.27) (thickness 0.15)) (justify left bottom) hide)
    )
    (property "License" "Apache-2.0" (id 7) (at 393.7 229.235 0)
      (effects (font (size 1.27 1.27) (thickness 0.15)) (justify left bottom) hide)
    )
    (pin "1")
    (pin "2")
  )

  (symbol (lib_id "sa800u-baseboard-hw:R_10k_0402") (at 386.08 206.375 180) (unit 1)
    (in_bom yes) (on_board yes) (fields_autoplaced)
    (property "Reference" "R77" (id 0) (at 383.54 199.39 0)
      (effects (font (size 1.524 1.524)))
    )
    (property "Value" "R_10k_0402" (id 1) (at 386.08 202.565 0)
      (effects (font (size 1.524 1.524)) hide)
    )
    (property "Footprint" "sa800u-baseboard-hw-footprints:R_0402_1005Metric" (id 2) (at 381 211.455 0)
      (effects (font (size 1.524 1.524)) (justify left) hide)
    )
    (property "Datasheet" "https://www.bourns.com/docs/product-datasheets/cr.pdf" (id 3) (at 386.08 206.375 0)
      (effects (font (size 1.27 1.27)) hide)
    )
    (property "Manufacturer" "Bourns" (id 4) (at 381 216.535 0)
      (effects (font (size 1.524 1.524)) (justify left) hide)
    )
    (property "MPN" "CR0402-FX-1002GLF" (id 5) (at 381 213.995 0)
      (effects (font (size 1.524 1.524)) (justify left) hide)
    )
    (property "Val" "10k" (id 6) (at 383.54 203.2 0))
    (property "License" "Apache-2.0" (id 7) (at 365.76 180.975 0)
      (effects (font (size 1.27 1.27) (thickness 0.15)) (justify left bottom) hide)
    )
    (property "Author" "Antmicro" (id 8) (at 365.76 178.435 0)
      (effects (font (size 1.27 1.27) (thickness 0.15)) (justify left bottom) hide)
    )
    (property "Tolerance" "1%" (id 9) (at 365.76 196.215 0)
      (effects (font (size 1.27 1.27)) (justify left bottom) hide)
    )
    (pin "1")
    (pin "2")
  )

  (symbol (lib_id "sa800u-baseboard-hw:GND") (at 387.35 220.345 0) (unit 1)
    (in_bom yes) (on_board yes) (fields_autoplaced)
    (property "Reference" "#PWR0165" (id 0) (at 387.35 226.695 0)
      (effects (font (size 1.27 1.27)) hide)
    )
    (property "Value" "GND" (id 1) (at 387.35 224.79 0))
    (property "Footprint" "" (id 2) (at 387.35 220.345 0)
      (effects (font (size 1.27 1.27)) hide)
    )
    (property "Datasheet" "" (id 3) (at 387.35 220.345 0)
      (effects (font (size 1.27 1.27)) hide)
    )
    (property "Author" "Antmicro" (id 4) (at 396.24 227.965 0)
      (effects (font (size 1.27 1.27) (thickness 0.15)) (justify left bottom) hide)
    )
    (property "License" "Apache-2.0" (id 5) (at 396.24 230.505 0)
      (effects (font (size 1.27 1.27) (thickness 0.15)) (justify left bottom) hide)
    )
    (pin "1")
  )

  (symbol (lib_id "sa800u-baseboard-hw:LED_G_0603_KP-1608ZGC") (at 371.475 232.41 0) (unit 1)
    (in_bom yes) (on_board yes) (fields_autoplaced)
    (property "Reference" "D16" (id 0) (at 375.285 228.6 0)
      (effects (font (size 1.524 1.524)))
    )
    (property "Value" "KP-1608EC" (id 1) (at 370.205 226.5426 0)
      (effects (font (size 1.524 1.524)) hide)
    )
    (property "Footprint" "sa800u-baseboard-hw-footprints:LED_0603_1608Metric_G" (id 2) (at 394.335 242.57 0)
      (effects (font (size 1.27 1.27) (thickness 0.15)) (justify left bottom) hide)
    )
    (property "Datasheet" "https://www.farnell.com/datasheets/2045914.pdf" (id 3) (at 394.335 245.11 0)
      (effects (font (size 1.27 1.27) (thickness 0.15)) (justify left bottom) hide)
    )
    (property "MPN" "KP-1608ZGC" (id 4) (at 394.335 247.65 0)
      (effects (font (size 1.27 1.27) (thickness 0.15)) (justify left bottom) hide)
    )
    (property "Manufacturer" "Kingbright" (id 5) (at 394.335 250.19 0)
      (effects (font (size 1.27 1.27) (thickness 0.15)) (justify left bottom) hide)
    )
    (property "Author" "Antmicro" (id 6) (at 394.335 252.73 0)
      (effects (font (size 1.27 1.27) (thickness 0.15)) (justify left bottom) hide)
    )
    (property "License" "Apache-2.0" (id 7) (at 394.335 255.27 0)
      (effects (font (size 1.27 1.27) (thickness 0.15)) (justify left bottom) hide)
    )
    (pin "1")
    (pin "2")
  )

  (symbol (lib_id "sa800u-baseboard-hw:R_10k_0402") (at 386.715 232.41 180) (unit 1)
    (in_bom yes) (on_board yes) (fields_autoplaced)
    (property "Reference" "R79" (id 0) (at 384.175 226.06 0)
      (effects (font (size 1.524 1.524)))
    )
    (property "Value" "R_10k_0402" (id 1) (at 386.715 228.6 0)
      (effects (font (size 1.524 1.524)) hide)
    )
    (property "Footprint" "sa800u-baseboard-hw-footprints:R_0402_1005Metric" (id 2) (at 381.635 237.49 0)
      (effects (font (size 1.524 1.524)) (justify left) hide)
    )
    (property "Datasheet" "https://www.bourns.com/docs/product-datasheets/cr.pdf" (id 3) (at 386.715 232.41 0)
      (effects (font (size 1.27 1.27)) hide)
    )
    (property "Manufacturer" "Bourns" (id 4) (at 381.635 242.57 0)
      (effects (font (size 1.524 1.524)) (justify left) hide)
    )
    (property "MPN" "CR0402-FX-1002GLF" (id 5) (at 381.635 240.03 0)
      (effects (font (size 1.524 1.524)) (justify left) hide)
    )
    (property "Val" "10k" (id 6) (at 384.175 228.6 0))
    (property "License" "Apache-2.0" (id 7) (at 366.395 207.01 0)
      (effects (font (size 1.27 1.27) (thickness 0.15)) (justify left bottom) hide)
    )
    (property "Author" "Antmicro" (id 8) (at 366.395 204.47 0)
      (effects (font (size 1.27 1.27) (thickness 0.15)) (justify left bottom) hide)
    )
    (property "Tolerance" "1%" (id 9) (at 366.395 222.25 0)
      (effects (font (size 1.27 1.27)) (justify left bottom) hide)
    )
    (pin "1")
    (pin "2")
  )

  (symbol (lib_id "sa800u-baseboard-hw:GND") (at 387.985 246.38 0) (unit 1)
    (in_bom yes) (on_board yes) (fields_autoplaced)
    (property "Reference" "#PWR0167" (id 0) (at 387.985 252.73 0)
      (effects (font (size 1.27 1.27)) hide)
    )
    (property "Value" "GND" (id 1) (at 387.985 251.46 0))
    (property "Footprint" "" (id 2) (at 387.985 246.38 0)
      (effects (font (size 1.27 1.27)) hide)
    )
    (property "Datasheet" "" (id 3) (at 387.985 246.38 0)
      (effects (font (size 1.27 1.27)) hide)
    )
    (property "Author" "Antmicro" (id 4) (at 396.875 254 0)
      (effects (font (size 1.27 1.27) (thickness 0.15)) (justify left bottom) hide)
    )
    (property "License" "Apache-2.0" (id 5) (at 396.875 256.54 0)
      (effects (font (size 1.27 1.27) (thickness 0.15)) (justify left bottom) hide)
    )
    (pin "1")
  )

  (symbol (lib_id "sa800u-baseboard-hw:BSS138PW") (at 380.365 191.77 0) (unit 1)
    (in_bom yes) (on_board yes) (fields_autoplaced)
    (property "Reference" "Q6" (id 0) (at 391.16 187.96 0)
      (effects (font (size 1.524 1.524)) (justify left))
    )
    (property "Value" "BSS138PW" (id 1) (at 391.16 191.77 0)
      (effects (font (size 1.524 1.524)) (justify left))
    )
    (property "Footprint" "sa800u-baseboard-hw-footprints:SC70-3" (id 2) (at 385.445 186.69 0)
      (effects (font (size 1.524 1.524)) (justify left) hide)
    )
    (property "Datasheet" "https://assets.nexperia.com/documents/data-sheet/BSS138PW.pdf" (id 3) (at 385.445 184.15 0)
      (effects (font (size 1.524 1.524)) (justify left) hide)
    )
    (property "MPN" "BSS138PW" (id 4) (at 385.445 179.07 0)
      (effects (font (size 1.524 1.524)) (justify left) hide)
    )
    (property "Manufacturer" "Nexperia" (id 5) (at 385.445 163.83 0)
      (effects (font (size 1.524 1.524)) (justify left) hide)
    )
    (property "Author" "Antmicro" (id 6) (at 403.225 213.36 0)
      (effects (font (size 1.27 1.27) (thickness 0.15)) (justify left bottom) hide)
    )
    (property "License" "Apache-2.0" (id 7) (at 403.225 215.9 0)
      (effects (font (size 1.27 1.27) (thickness 0.15)) (justify left bottom) hide)
    )
    (pin "1")
    (pin "2")
    (pin "3")
  )

  (symbol (lib_id "sa800u-baseboard-hw:BSS138PW") (at 379.73 216.535 0) (unit 1)
    (in_bom yes) (on_board yes) (fields_autoplaced)
    (property "Reference" "Q5" (id 0) (at 391.16 212.725 0)
      (effects (font (size 1.524 1.524)) (justify left))
    )
    (property "Value" "BSS138PW" (id 1) (at 391.16 216.535 0)
      (effects (font (size 1.524 1.524)) (justify left))
    )
    (property "Footprint" "sa800u-baseboard-hw-footprints:SC70-3" (id 2) (at 384.81 211.455 0)
      (effects (font (size 1.524 1.524)) (justify left) hide)
    )
    (property "Datasheet" "https://assets.nexperia.com/documents/data-sheet/BSS138PW.pdf" (id 3) (at 384.81 208.915 0)
      (effects (font (size 1.524 1.524)) (justify left) hide)
    )
    (property "MPN" "BSS138PW" (id 4) (at 384.81 203.835 0)
      (effects (font (size 1.524 1.524)) (justify left) hide)
    )
    (property "Manufacturer" "Nexperia" (id 5) (at 384.81 188.595 0)
      (effects (font (size 1.524 1.524)) (justify left) hide)
    )
    (property "Author" "Antmicro" (id 6) (at 402.59 238.125 0)
      (effects (font (size 1.27 1.27) (thickness 0.15)) (justify left bottom) hide)
    )
    (property "License" "Apache-2.0" (id 7) (at 402.59 240.665 0)
      (effects (font (size 1.27 1.27) (thickness 0.15)) (justify left bottom) hide)
    )
    (pin "1")
    (pin "2")
    (pin "3")
  )

  (symbol (lib_id "sa800u-baseboard-hw:BSS138PW") (at 380.365 242.57 0) (unit 1)
    (in_bom yes) (on_board yes) (fields_autoplaced)
    (property "Reference" "Q7" (id 0) (at 391.16 238.76 0)
      (effects (font (size 1.524 1.524)) (justify left))
    )
    (property "Value" "BSS138PW" (id 1) (at 391.16 242.57 0)
      (effects (font (size 1.524 1.524)) (justify left))
    )
    (property "Footprint" "sa800u-baseboard-hw-footprints:SC70-3" (id 2) (at 385.445 237.49 0)
      (effects (font (size 1.524 1.524)) (justify left) hide)
    )
    (property "Datasheet" "https://assets.nexperia.com/documents/data-sheet/BSS138PW.pdf" (id 3) (at 385.445 234.95 0)
      (effects (font (size 1.524 1.524)) (justify left) hide)
    )
    (property "MPN" "BSS138PW" (id 4) (at 385.445 229.87 0)
      (effects (font (size 1.524 1.524)) (justify left) hide)
    )
    (property "Manufacturer" "Nexperia" (id 5) (at 385.445 214.63 0)
      (effects (font (size 1.524 1.524)) (justify left) hide)
    )
    (property "Author" "Antmicro" (id 6) (at 403.225 264.16 0)
      (effects (font (size 1.27 1.27) (thickness 0.15)) (justify left bottom) hide)
    )
    (property "License" "Apache-2.0" (id 7) (at 403.225 266.7 0)
      (effects (font (size 1.27 1.27) (thickness 0.15)) (justify left bottom) hide)
    )
    (pin "1")
    (pin "2")
    (pin "3")
  )

  (symbol (lib_id "sa800u-baseboard-hw:GND") (at 287.909 276.86 0) (unit 1)
    (in_bom yes) (on_board yes) (fields_autoplaced)
    (property "Reference" "#PWR0102" (id 0) (at 287.909 283.21 0)
      (effects (font (size 1.27 1.27)) hide)
    )
    (property "Value" "GND" (id 1) (at 287.909 281.94 0))
    (property "Footprint" "" (id 2) (at 287.909 276.86 0)
      (effects (font (size 1.27 1.27)) hide)
    )
    (property "Datasheet" "" (id 3) (at 287.909 276.86 0)
      (effects (font (size 1.27 1.27)) hide)
    )
    (property "Author" "Antmicro" (id 4) (at 296.799 284.48 0)
      (effects (font (size 1.27 1.27) (thickness 0.15)) (justify left bottom) hide)
    )
    (property "License" "Apache-2.0" (id 5) (at 296.799 287.02 0)
      (effects (font (size 1.27 1.27) (thickness 0.15)) (justify left bottom) hide)
    )
    (pin "1")
  )

  (symbol (lib_id "sa800u-baseboard-hw:PWR_FLAG") (at 51.181 187.325 0) (unit 1)
    (in_bom yes) (on_board yes)
    (property "Reference" "#FLG0109" (id 0) (at 51.181 185.42 0)
      (effects (font (size 1.27 1.27)) hide)
    )
    (property "Value" "PWR_FLAG" (id 1) (at 51.181 183.769 0))
    (property "Footprint" "" (id 2) (at 51.181 187.325 0)
      (effects (font (size 1.27 1.27)) hide)
    )
    (property "Datasheet" "~" (id 3) (at 51.181 187.325 0)
      (effects (font (size 1.27 1.27)) hide)
    )
    (pin "1")
  )

  (symbol (lib_id "sa800u-baseboard-hw:Receptacle_SA800U-WF") (at 207.645 29.21 0) (unit 2)
    (in_bom yes) (on_board yes) (fields_autoplaced)
    (property "Reference" "U11" (id 0) (at 232.41 21.59 0)
      (effects (font (size 1.27 1.27) (thickness 0.15)))
    )
    (property "Value" "Receptacle_SA800U-WF" (id 1) (at 271.145 39.37 0)
      (effects (font (size 1.27 1.27) (thickness 0.15)) (justify left bottom) hide)
    )
    (property "Footprint" "sa800u-baseboard-hw-footprints:Receptacle_SA800U-WF" (id 2) (at 271.145 41.91 0)
      (effects (font (size 1.27 1.27) (thickness 0.15)) (justify left bottom) hide)
    )
    (property "Datasheet" "https://www.farnell.com/datasheets/2691101.pdf" (id 3) (at 271.145 44.45 0)
      (effects (font (size 1.27 1.27) (thickness 0.15)) (justify left bottom) hide)
    )
    (property "MPN" "FX10A-168S-SV" (id 4) (at 232.41 24.13 0)
      (effects (font (size 1.27 1.27) (thickness 0.15)))
    )
    (property "Manufacturer" "Hirose Electric" (id 5) (at 271.145 46.99 0)
      (effects (font (size 1.27 1.27) (thickness 0.15)) (justify left bottom) hide)
    )
    (property "Author" "Antmicro" (id 6) (at 271.145 49.53 0)
      (effects (font (size 1.27 1.27) (thickness 0.15)) (justify left bottom) hide)
    )
    (property "License" "Apache-2.0" (id 7) (at 271.145 52.07 0)
      (effects (font (size 1.27 1.27) (thickness 0.15)) (justify left bottom) hide)
    )
    (pin "1_1")
    (pin "1_10")
    (pin "1_100")
    (pin "1_101")
    (pin "1_102")
    (pin "1_103")
    (pin "1_104")
    (pin "1_105")
    (pin "1_106")
    (pin "1_107")
    (pin "1_108")
    (pin "1_109")
    (pin "1_11")
    (pin "1_110")
    (pin "1_111")
    (pin "1_112")
    (pin "1_113")
    (pin "1_114")
    (pin "1_115")
    (pin "1_116")
    (pin "1_117")
    (pin "1_118")
    (pin "1_119")
    (pin "1_12")
    (pin "1_120")
    (pin "1_121")
    (pin "1_122")
    (pin "1_123")
    (pin "1_124")
    (pin "1_125")
    (pin "1_126")
    (pin "1_127")
    (pin "1_128")
    (pin "1_129")
    (pin "1_13")
    (pin "1_130")
    (pin "1_131")
    (pin "1_132")
    (pin "1_133")
    (pin "1_134")
    (pin "1_135")
    (pin "1_136")
    (pin "1_137")
    (pin "1_138")
    (pin "1_139")
    (pin "1_14")
    (pin "1_140")
    (pin "1_141")
    (pin "1_142")
    (pin "1_143")
    (pin "1_144")
    (pin "1_145")
    (pin "1_146")
    (pin "1_147")
    (pin "1_148")
    (pin "1_149")
    (pin "1_15")
    (pin "1_150")
    (pin "1_151")
    (pin "1_152")
    (pin "1_153")
    (pin "1_154")
    (pin "1_155")
    (pin "1_156")
    (pin "1_157")
    (pin "1_158")
    (pin "1_159")
    (pin "1_16")
    (pin "1_160")
    (pin "1_161")
    (pin "1_162")
    (pin "1_163")
    (pin "1_164")
    (pin "1_165")
    (pin "1_166")
    (pin "1_167")
    (pin "1_168")
    (pin "1_17")
    (pin "1_171")
    (pin "1_172")
    (pin "1_18")
    (pin "1_19")
    (pin "1_2")
    (pin "1_20")
    (pin "1_21")
    (pin "1_22")
    (pin "1_23")
    (pin "1_24")
    (pin "1_25")
    (pin "1_26")
    (pin "1_27")
    (pin "1_28")
    (pin "1_29")
    (pin "1_3")
    (pin "1_30")
    (pin "1_31")
    (pin "1_32")
    (pin "1_33")
    (pin "1_34")
    (pin "1_35")
    (pin "1_36")
    (pin "1_37")
    (pin "1_38")
    (pin "1_39")
    (pin "1_4")
    (pin "1_40")
    (pin "1_41")
    (pin "1_42")
    (pin "1_43")
    (pin "1_44")
    (pin "1_45")
    (pin "1_46")
    (pin "1_47")
    (pin "1_48")
    (pin "1_49")
    (pin "1_5")
    (pin "1_50")
    (pin "1_51")
    (pin "1_52")
    (pin "1_53")
    (pin "1_54")
    (pin "1_55")
    (pin "1_56")
    (pin "1_57")
    (pin "1_58")
    (pin "1_59")
    (pin "1_6")
    (pin "1_60")
    (pin "1_61")
    (pin "1_62")
    (pin "1_63")
    (pin "1_64")
    (pin "1_65")
    (pin "1_66")
    (pin "1_67")
    (pin "1_68")
    (pin "1_69")
    (pin "1_7")
    (pin "1_70")
    (pin "1_71")
    (pin "1_72")
    (pin "1_73")
    (pin "1_74")
    (pin "1_75")
    (pin "1_76")
    (pin "1_77")
    (pin "1_78")
    (pin "1_79")
    (pin "1_8")
    (pin "1_80")
    (pin "1_81")
    (pin "1_82")
    (pin "1_83")
    (pin "1_84")
    (pin "1_85")
    (pin "1_86")
    (pin "1_87")
    (pin "1_88")
    (pin "1_89")
    (pin "1_9")
    (pin "1_90")
    (pin "1_91")
    (pin "1_92")
    (pin "1_93")
    (pin "1_94")
    (pin "1_95")
    (pin "1_96")
    (pin "1_97")
    (pin "1_98")
    (pin "1_99")
    (pin "2_1")
    (pin "2_10")
    (pin "2_100")
    (pin "2_101")
    (pin "2_102")
    (pin "2_103")
    (pin "2_104")
    (pin "2_105")
    (pin "2_106")
    (pin "2_107")
    (pin "2_108")
    (pin "2_109")
    (pin "2_11")
    (pin "2_110")
    (pin "2_111")
    (pin "2_112")
    (pin "2_113")
    (pin "2_114")
    (pin "2_115")
    (pin "2_116")
    (pin "2_117")
    (pin "2_118")
    (pin "2_119")
    (pin "2_12")
    (pin "2_120")
    (pin "2_121")
    (pin "2_122")
    (pin "2_123")
    (pin "2_124")
    (pin "2_125")
    (pin "2_126")
    (pin "2_127")
    (pin "2_128")
    (pin "2_129")
    (pin "2_13")
    (pin "2_130")
    (pin "2_131")
    (pin "2_132")
    (pin "2_133")
    (pin "2_134")
    (pin "2_135")
    (pin "2_136")
    (pin "2_137")
    (pin "2_138")
    (pin "2_139")
    (pin "2_14")
    (pin "2_140")
    (pin "2_141")
    (pin "2_142")
    (pin "2_143")
    (pin "2_144")
    (pin "2_145")
    (pin "2_146")
    (pin "2_147")
    (pin "2_148")
    (pin "2_149")
    (pin "2_15")
    (pin "2_150")
    (pin "2_151")
    (pin "2_152")
    (pin "2_153")
    (pin "2_154")
    (pin "2_155")
    (pin "2_156")
    (pin "2_157")
    (pin "2_158")
    (pin "2_159")
    (pin "2_16")
    (pin "2_160")
    (pin "2_161")
    (pin "2_162")
    (pin "2_163")
    (pin "2_164")
    (pin "2_165")
    (pin "2_166")
    (pin "2_167")
    (pin "2_168")
    (pin "2_17")
    (pin "2_171")
    (pin "2_172")
    (pin "2_18")
    (pin "2_19")
    (pin "2_2")
    (pin "2_20")
    (pin "2_21")
    (pin "2_22")
    (pin "2_23")
    (pin "2_24")
    (pin "2_25")
    (pin "2_26")
    (pin "2_27")
    (pin "2_28")
    (pin "2_29")
    (pin "2_3")
    (pin "2_30")
    (pin "2_31")
    (pin "2_32")
    (pin "2_33")
    (pin "2_34")
    (pin "2_35")
    (pin "2_36")
    (pin "2_37")
    (pin "2_38")
    (pin "2_39")
    (pin "2_4")
    (pin "2_40")
    (pin "2_41")
    (pin "2_42")
    (pin "2_43")
    (pin "2_44")
    (pin "2_45")
    (pin "2_46")
    (pin "2_47")
    (pin "2_48")
    (pin "2_49")
    (pin "2_5")
    (pin "2_50")
    (pin "2_51")
    (pin "2_52")
    (pin "2_53")
    (pin "2_54")
    (pin "2_55")
    (pin "2_56")
    (pin "2_57")
    (pin "2_58")
    (pin "2_59")
    (pin "2_6")
    (pin "2_60")
    (pin "2_61")
    (pin "2_62")
    (pin "2_63")
    (pin "2_64")
    (pin "2_65")
    (pin "2_66")
    (pin "2_67")
    (pin "2_68")
    (pin "2_69")
    (pin "2_7")
    (pin "2_70")
    (pin "2_71")
    (pin "2_72")
    (pin "2_73")
    (pin "2_74")
    (pin "2_75")
    (pin "2_76")
    (pin "2_77")
    (pin "2_78")
    (pin "2_79")
    (pin "2_8")
    (pin "2_80")
    (pin "2_81")
    (pin "2_82")
    (pin "2_83")
    (pin "2_84")
    (pin "2_85")
    (pin "2_86")
    (pin "2_87")
    (pin "2_88")
    (pin "2_89")
    (pin "2_9")
    (pin "2_90")
    (pin "2_91")
    (pin "2_92")
    (pin "2_93")
    (pin "2_94")
    (pin "2_95")
    (pin "2_96")
    (pin "2_97")
    (pin "2_98")
    (pin "2_99")
    (pin "3_1")
    (pin "3_10")
    (pin "3_11")
    (pin "3_12")
    (pin "3_13")
    (pin "3_14")
    (pin "3_15")
    (pin "3_16")
    (pin "3_17")
    (pin "3_18")
    (pin "3_19")
    (pin "3_2")
    (pin "3_20")
    (pin "3_21")
    (pin "3_22")
    (pin "3_23")
    (pin "3_24")
    (pin "3_25")
    (pin "3_26")
    (pin "3_27")
    (pin "3_28")
    (pin "3_29")
    (pin "3_3")
    (pin "3_30")
    (pin "3_31")
    (pin "3_32")
    (pin "3_33")
    (pin "3_34")
    (pin "3_4")
    (pin "3_5")
    (pin "3_6")
    (pin "3_7")
    (pin "3_8")
    (pin "3_9")
    (pin "4_1")
    (pin "4_10")
    (pin "4_11")
    (pin "4_12")
    (pin "4_13")
    (pin "4_14")
    (pin "4_15")
    (pin "4_16")
    (pin "4_17")
    (pin "4_18")
    (pin "4_19")
    (pin "4_2")
    (pin "4_20")
    (pin "4_21")
    (pin "4_22")
    (pin "4_23")
    (pin "4_24")
    (pin "4_25")
    (pin "4_26")
    (pin "4_27")
    (pin "4_28")
    (pin "4_29")
    (pin "4_3")
    (pin "4_30")
    (pin "4_31")
    (pin "4_32")
    (pin "4_33")
    (pin "4_34")
    (pin "4_4")
    (pin "4_5")
    (pin "4_6")
    (pin "4_7")
    (pin "4_8")
    (pin "4_9")
  )

  (symbol (lib_id "sa800u-baseboard-hw:Receptacle_SA800U-WF") (at 57.785 30.48 0) (unit 1)
    (in_bom yes) (on_board yes) (fields_autoplaced)
    (property "Reference" "U11" (id 0) (at 82.55 22.86 0)
      (effects (font (size 1.27 1.27) (thickness 0.15)))
    )
    (property "Value" "Receptacle_SA800U-WF" (id 1) (at 121.285 40.64 0)
      (effects (font (size 1.27 1.27) (thickness 0.15)) (justify left bottom) hide)
    )
    (property "Footprint" "sa800u-baseboard-hw-footprints:Receptacle_SA800U-WF" (id 2) (at 121.285 43.18 0)
      (effects (font (size 1.27 1.27) (thickness 0.15)) (justify left bottom) hide)
    )
    (property "Datasheet" "https://www.farnell.com/datasheets/2691101.pdf" (id 3) (at 121.285 45.72 0)
      (effects (font (size 1.27 1.27) (thickness 0.15)) (justify left bottom) hide)
    )
    (property "MPN" "FX10A-168S-SV" (id 4) (at 82.55 25.4 0)
      (effects (font (size 1.27 1.27) (thickness 0.15)))
    )
    (property "Manufacturer" "Hirose Electric" (id 5) (at 121.285 48.26 0)
      (effects (font (size 1.27 1.27) (thickness 0.15)) (justify left bottom) hide)
    )
    (property "Author" "Antmicro" (id 6) (at 121.285 50.8 0)
      (effects (font (size 1.27 1.27) (thickness 0.15)) (justify left bottom) hide)
    )
    (property "License" "Apache-2.0" (id 7) (at 121.285 53.34 0)
      (effects (font (size 1.27 1.27) (thickness 0.15)) (justify left bottom) hide)
    )
    (pin "1_1")
    (pin "1_10")
    (pin "1_100")
    (pin "1_101")
    (pin "1_102")
    (pin "1_103")
    (pin "1_104")
    (pin "1_105")
    (pin "1_106")
    (pin "1_107")
    (pin "1_108")
    (pin "1_109")
    (pin "1_11")
    (pin "1_110")
    (pin "1_111")
    (pin "1_112")
    (pin "1_113")
    (pin "1_114")
    (pin "1_115")
    (pin "1_116")
    (pin "1_117")
    (pin "1_118")
    (pin "1_119")
    (pin "1_12")
    (pin "1_120")
    (pin "1_121")
    (pin "1_122")
    (pin "1_123")
    (pin "1_124")
    (pin "1_125")
    (pin "1_126")
    (pin "1_127")
    (pin "1_128")
    (pin "1_129")
    (pin "1_13")
    (pin "1_130")
    (pin "1_131")
    (pin "1_132")
    (pin "1_133")
    (pin "1_134")
    (pin "1_135")
    (pin "1_136")
    (pin "1_137")
    (pin "1_138")
    (pin "1_139")
    (pin "1_14")
    (pin "1_140")
    (pin "1_141")
    (pin "1_142")
    (pin "1_143")
    (pin "1_144")
    (pin "1_145")
    (pin "1_146")
    (pin "1_147")
    (pin "1_148")
    (pin "1_149")
    (pin "1_15")
    (pin "1_150")
    (pin "1_151")
    (pin "1_152")
    (pin "1_153")
    (pin "1_154")
    (pin "1_155")
    (pin "1_156")
    (pin "1_157")
    (pin "1_158")
    (pin "1_159")
    (pin "1_16")
    (pin "1_160")
    (pin "1_161")
    (pin "1_162")
    (pin "1_163")
    (pin "1_164")
    (pin "1_165")
    (pin "1_166")
    (pin "1_167")
    (pin "1_168")
    (pin "1_17")
    (pin "1_171")
    (pin "1_172")
    (pin "1_18")
    (pin "1_19")
    (pin "1_2")
    (pin "1_20")
    (pin "1_21")
    (pin "1_22")
    (pin "1_23")
    (pin "1_24")
    (pin "1_25")
    (pin "1_26")
    (pin "1_27")
    (pin "1_28")
    (pin "1_29")
    (pin "1_3")
    (pin "1_30")
    (pin "1_31")
    (pin "1_32")
    (pin "1_33")
    (pin "1_34")
    (pin "1_35")
    (pin "1_36")
    (pin "1_37")
    (pin "1_38")
    (pin "1_39")
    (pin "1_4")
    (pin "1_40")
    (pin "1_41")
    (pin "1_42")
    (pin "1_43")
    (pin "1_44")
    (pin "1_45")
    (pin "1_46")
    (pin "1_47")
    (pin "1_48")
    (pin "1_49")
    (pin "1_5")
    (pin "1_50")
    (pin "1_51")
    (pin "1_52")
    (pin "1_53")
    (pin "1_54")
    (pin "1_55")
    (pin "1_56")
    (pin "1_57")
    (pin "1_58")
    (pin "1_59")
    (pin "1_6")
    (pin "1_60")
    (pin "1_61")
    (pin "1_62")
    (pin "1_63")
    (pin "1_64")
    (pin "1_65")
    (pin "1_66")
    (pin "1_67")
    (pin "1_68")
    (pin "1_69")
    (pin "1_7")
    (pin "1_70")
    (pin "1_71")
    (pin "1_72")
    (pin "1_73")
    (pin "1_74")
    (pin "1_75")
    (pin "1_76")
    (pin "1_77")
    (pin "1_78")
    (pin "1_79")
    (pin "1_8")
    (pin "1_80")
    (pin "1_81")
    (pin "1_82")
    (pin "1_83")
    (pin "1_84")
    (pin "1_85")
    (pin "1_86")
    (pin "1_87")
    (pin "1_88")
    (pin "1_89")
    (pin "1_9")
    (pin "1_90")
    (pin "1_91")
    (pin "1_92")
    (pin "1_93")
    (pin "1_94")
    (pin "1_95")
    (pin "1_96")
    (pin "1_97")
    (pin "1_98")
    (pin "1_99")
    (pin "2_1")
    (pin "2_10")
    (pin "2_100")
    (pin "2_101")
    (pin "2_102")
    (pin "2_103")
    (pin "2_104")
    (pin "2_105")
    (pin "2_106")
    (pin "2_107")
    (pin "2_108")
    (pin "2_109")
    (pin "2_11")
    (pin "2_110")
    (pin "2_111")
    (pin "2_112")
    (pin "2_113")
    (pin "2_114")
    (pin "2_115")
    (pin "2_116")
    (pin "2_117")
    (pin "2_118")
    (pin "2_119")
    (pin "2_12")
    (pin "2_120")
    (pin "2_121")
    (pin "2_122")
    (pin "2_123")
    (pin "2_124")
    (pin "2_125")
    (pin "2_126")
    (pin "2_127")
    (pin "2_128")
    (pin "2_129")
    (pin "2_13")
    (pin "2_130")
    (pin "2_131")
    (pin "2_132")
    (pin "2_133")
    (pin "2_134")
    (pin "2_135")
    (pin "2_136")
    (pin "2_137")
    (pin "2_138")
    (pin "2_139")
    (pin "2_14")
    (pin "2_140")
    (pin "2_141")
    (pin "2_142")
    (pin "2_143")
    (pin "2_144")
    (pin "2_145")
    (pin "2_146")
    (pin "2_147")
    (pin "2_148")
    (pin "2_149")
    (pin "2_15")
    (pin "2_150")
    (pin "2_151")
    (pin "2_152")
    (pin "2_153")
    (pin "2_154")
    (pin "2_155")
    (pin "2_156")
    (pin "2_157")
    (pin "2_158")
    (pin "2_159")
    (pin "2_16")
    (pin "2_160")
    (pin "2_161")
    (pin "2_162")
    (pin "2_163")
    (pin "2_164")
    (pin "2_165")
    (pin "2_166")
    (pin "2_167")
    (pin "2_168")
    (pin "2_17")
    (pin "2_171")
    (pin "2_172")
    (pin "2_18")
    (pin "2_19")
    (pin "2_2")
    (pin "2_20")
    (pin "2_21")
    (pin "2_22")
    (pin "2_23")
    (pin "2_24")
    (pin "2_25")
    (pin "2_26")
    (pin "2_27")
    (pin "2_28")
    (pin "2_29")
    (pin "2_3")
    (pin "2_30")
    (pin "2_31")
    (pin "2_32")
    (pin "2_33")
    (pin "2_34")
    (pin "2_35")
    (pin "2_36")
    (pin "2_37")
    (pin "2_38")
    (pin "2_39")
    (pin "2_4")
    (pin "2_40")
    (pin "2_41")
    (pin "2_42")
    (pin "2_43")
    (pin "2_44")
    (pin "2_45")
    (pin "2_46")
    (pin "2_47")
    (pin "2_48")
    (pin "2_49")
    (pin "2_5")
    (pin "2_50")
    (pin "2_51")
    (pin "2_52")
    (pin "2_53")
    (pin "2_54")
    (pin "2_55")
    (pin "2_56")
    (pin "2_57")
    (pin "2_58")
    (pin "2_59")
    (pin "2_6")
    (pin "2_60")
    (pin "2_61")
    (pin "2_62")
    (pin "2_63")
    (pin "2_64")
    (pin "2_65")
    (pin "2_66")
    (pin "2_67")
    (pin "2_68")
    (pin "2_69")
    (pin "2_7")
    (pin "2_70")
    (pin "2_71")
    (pin "2_72")
    (pin "2_73")
    (pin "2_74")
    (pin "2_75")
    (pin "2_76")
    (pin "2_77")
    (pin "2_78")
    (pin "2_79")
    (pin "2_8")
    (pin "2_80")
    (pin "2_81")
    (pin "2_82")
    (pin "2_83")
    (pin "2_84")
    (pin "2_85")
    (pin "2_86")
    (pin "2_87")
    (pin "2_88")
    (pin "2_89")
    (pin "2_9")
    (pin "2_90")
    (pin "2_91")
    (pin "2_92")
    (pin "2_93")
    (pin "2_94")
    (pin "2_95")
    (pin "2_96")
    (pin "2_97")
    (pin "2_98")
    (pin "2_99")
    (pin "3_1")
    (pin "3_10")
    (pin "3_11")
    (pin "3_12")
    (pin "3_13")
    (pin "3_14")
    (pin "3_15")
    (pin "3_16")
    (pin "3_17")
    (pin "3_18")
    (pin "3_19")
    (pin "3_2")
    (pin "3_20")
    (pin "3_21")
    (pin "3_22")
    (pin "3_23")
    (pin "3_24")
    (pin "3_25")
    (pin "3_26")
    (pin "3_27")
    (pin "3_28")
    (pin "3_29")
    (pin "3_3")
    (pin "3_30")
    (pin "3_31")
    (pin "3_32")
    (pin "3_33")
    (pin "3_34")
    (pin "3_4")
    (pin "3_5")
    (pin "3_6")
    (pin "3_7")
    (pin "3_8")
    (pin "3_9")
    (pin "4_1")
    (pin "4_10")
    (pin "4_11")
    (pin "4_12")
    (pin "4_13")
    (pin "4_14")
    (pin "4_15")
    (pin "4_16")
    (pin "4_17")
    (pin "4_18")
    (pin "4_19")
    (pin "4_2")
    (pin "4_20")
    (pin "4_21")
    (pin "4_22")
    (pin "4_23")
    (pin "4_24")
    (pin "4_25")
    (pin "4_26")
    (pin "4_27")
    (pin "4_28")
    (pin "4_29")
    (pin "4_3")
    (pin "4_30")
    (pin "4_31")
    (pin "4_32")
    (pin "4_33")
    (pin "4_34")
    (pin "4_4")
    (pin "4_5")
    (pin "4_6")
    (pin "4_7")
    (pin "4_8")
    (pin "4_9")
  )

  (symbol (lib_id "sa800u-baseboard-hw:SA800U-WF") (at 339.344 25.146 0) (unit 1)
    (in_bom yes) (on_board yes) (fields_autoplaced)
    (property "Reference" "A1" (id 0) (at 358.267 28.9559 0)
      (effects (font (size 1.27 1.27) (thickness 0.15)) (justify left))
    )
    (property "Value" "SA800U-WF" (id 1) (at 358.267 31.4959 0)
      (effects (font (size 1.27 1.27) (thickness 0.15)) (justify left))
    )
    (property "Footprint" "sa800u-baseboard-hw-footprints:SA800U-WF" (id 2) (at 369.824 32.766 0)
      (effects (font (size 1.27 1.27) (thickness 0.15)) (justify left bottom) hide)
    )
    (property "Datasheet" "https://www.quectel.com/wp-content/uploads/2023/03/Quectel_Product_Brochure_V7.4.pdf" (id 3) (at 369.824 35.306 0)
      (effects (font (size 1.27 1.27) (thickness 0.15)) (justify left bottom) hide)
    )
    (property "MPN" "SA800U-WF" (id 4) (at 369.824 41.656 0)
      (effects (font (size 1.27 1.27)) (justify left) hide)
    )
    (property "Manufacturer" "Quectel" (id 5) (at 369.824 44.196 0)
      (effects (font (size 1.27 1.27)) (justify left) hide)
    )
    (property "Author" "Antmicro" (id 6) (at 369.824 37.846 0)
      (effects (font (size 1.27 1.27) (thickness 0.15)) (justify left bottom) hide)
    )
    (property "License" "Apache-2.0" (id 7) (at 369.824 40.386 0)
      (effects (font (size 1.27 1.27) (thickness 0.15)) (justify left bottom) hide)
    )
  )
)
